FILE_TYPE = MACRO_DRAWING;
SET COLOR_WIRE YELLOW;
SET COLOR_PROP ORANGE;
SET COLOR_DOT WHITE;
SET COLOR_ARC YELLOW;
SET COLOR_BODY GREEN;
SET COLOR_NOTE PURPLE;
SET PROP_DISPLAY VALUE;
SET PAGE_NUMBER P169;
FORCEADD OFFPAGE..1
(-7275 3850);
FORCEPROP 2 LAST $XR0 169 
J 0
(-7527 3850);
DISPLAY 0.638298 (-7527 3850);
PAINT MONO (-7527 3850);
FORCEPROP 2 LAST PATH I10
J 2
(-7325 3925);
DISPLAY 1.021277 (-7325 3925);
DISPLAY INVISIBLE (-7325 3925);
FORCEPROP 2 LAST CDS_LIB standard
J 2
(-7275 3850);
DISPLAY INVISIBLE (-7275 3850);
FORCEPROP 1 LAST COMMENT_BODY TRUE
J 0
(-7150 3750);
DISPLAY 0.872340 (-7150 3750);
PAINT GREEN (-7150 3750);
DISPLAY INVISIBLE (-7150 3750);
FORCEPROP 1 LAST OFFPAGE TRUE
J 0
(-6950 3725);
DISPLAY 0.872340 (-6950 3725);
PAINT GREEN (-6950 3725);
DISPLAY INVISIBLE (-6950 3725);
FORCEADD UNIVERSAL_GND..1
(-4000 5000);
FORCEPROP 3 LASTPIN (-4000 5050) SIG_NAME GND\g
J 0
(-3990 5060);
DISPLAY 0.659574 (-3990 5060);
PAINT MONO (-3990 5060);
DISPLAY INVISIBLE (-3990 5060);
FORCEPROP 2 LAST CDS_LIB pure_quanta_power
J 0
(-4000 5000);
DISPLAY INVISIBLE (-4000 5000);
FORCEPROP 1 LAST PATH I105
J 0
(-3925 5000);
DISPLAY 0.872340 (-3925 5000);
PAINT AQUA (-3925 5000);
DISPLAY INVISIBLE (-3925 5000);
FORCEPROP 1 LAST HDL_POWER GND
J 1
(-3975 4925);
DISPLAY 0.872340 (-3975 4925);
PAINT GREEN (-3975 4925);
DISPLAY INVISIBLE (-3975 4925);
FORCEADD Q_CAPP..1
(-2475 2900);
FORCEPROP 1 LAST LOCATION PC495
J 0
(-2425 3000);
DISPLAY 0.489362 (-2425 3000);
PAINT SKYBLUE (-2425 3000);
FORCEPROP 0 LAST $SEC 1
J 0
(-2425 3025);
DISPLAY 0.680851 (-2425 3025);
PAINT MONO (-2425 3025);
DISPLAY INVISIBLE (-2425 3025);
FORCEPROP 0 LAST CDS_SEC 1
J 0
(-2425 3025);
DISPLAY 1.021277 (-2425 3025);
DISPLAY INVISIBLE (-2425 3025);
FORCEPROP 1 LASTPIN (-2475 3000) $PN 1
J 0
(-2465 2985);
DISPLAY 0.489362 (-2465 2985);
PAINT MONO (-2465 2985);
FORCEPROP 1 LASTPIN (-2475 2800) $PN 2
J 0
(-2465 2785);
DISPLAY 0.489362 (-2465 2785);
PAINT MONO (-2465 2785);
FORCEPROP 1 LAST VOLTAGE 4V
J 0
(-2425 2850);
DISPLAY 0.489362 (-2425 2850);
PAINT SKYBLUE (-2425 2850);
FORCEPROP 1 LAST PACK_TYPE SMLF
J 0
(-2425 2750);
DISPLAY 0.489362 (-2425 2750);
PAINT SKYBLUE (-2425 2750);
FORCEPROP 1 LAST VALUE 220UF
J 0
(-2425 2950);
DISPLAY 0.489362 (-2425 2950);
PAINT SKYBLUE (-2425 2950);
FORCEPROP 1 LAST TOLERANCE 20%
J 0
(-2425 2900);
DISPLAY 0.489362 (-2425 2900);
PAINT SKYBLUE (-2425 2900);
FORCEPROP 1 LAST MATERIAL SPCAP
J 0
(-2425 2800);
DISPLAY 0.489362 (-2425 2800);
PAINT SKYBLUE (-2425 2800);
FORCEPROP 1 LAST PART_NUMBER CH122KM8801
J 0
(-2425 2700);
DISPLAY 0.489362 (-2425 2700);
PAINT SKYBLUE (-2425 2700);
FORCEPROP 1 LAST PATH I106
J 0
(-2425 3050);
DISPLAY 0.978723 (-2425 3050);
DISPLAY INVISIBLE (-2425 3050);
FORCEPROP 2 LAST CDS_LIB pure_quanta
J 0
(-2475 2900);
DISPLAY INVISIBLE (-2475 2900);
FORCEADD Q_CAPP..1
(-2800 2900);
FORCEPROP 1 LAST LOCATION PC494
J 0
(-2750 3000);
DISPLAY 0.489362 (-2750 3000);
PAINT SKYBLUE (-2750 3000);
FORCEPROP 0 LAST $SEC 1
J 0
(-2750 3025);
DISPLAY 0.680851 (-2750 3025);
PAINT MONO (-2750 3025);
DISPLAY INVISIBLE (-2750 3025);
FORCEPROP 0 LAST CDS_SEC 1
J 0
(-2750 3025);
DISPLAY 1.021277 (-2750 3025);
DISPLAY INVISIBLE (-2750 3025);
FORCEPROP 1 LASTPIN (-2800 3000) $PN 1
J 0
(-2790 2985);
DISPLAY 0.489362 (-2790 2985);
PAINT MONO (-2790 2985);
FORCEPROP 1 LASTPIN (-2800 2800) $PN 2
J 0
(-2790 2785);
DISPLAY 0.489362 (-2790 2785);
PAINT MONO (-2790 2785);
FORCEPROP 1 LAST PACK_TYPE SMLF
J 0
(-2750 2750);
DISPLAY 0.489362 (-2750 2750);
PAINT SKYBLUE (-2750 2750);
FORCEPROP 1 LAST VOLTAGE 4V
J 0
(-2750 2850);
DISPLAY 0.489362 (-2750 2850);
PAINT SKYBLUE (-2750 2850);
FORCEPROP 1 LAST MATERIAL SPCAP
J 0
(-2750 2800);
DISPLAY 0.489362 (-2750 2800);
PAINT SKYBLUE (-2750 2800);
FORCEPROP 1 LAST PART_NUMBER CH122KM8801
J 0
(-2750 2700);
DISPLAY 0.489362 (-2750 2700);
PAINT SKYBLUE (-2750 2700);
FORCEPROP 1 LAST TOLERANCE 20%
J 0
(-2750 2900);
DISPLAY 0.489362 (-2750 2900);
PAINT SKYBLUE (-2750 2900);
FORCEPROP 1 LAST VALUE 220UF
J 0
(-2750 2950);
DISPLAY 0.489362 (-2750 2950);
PAINT SKYBLUE (-2750 2950);
FORCEPROP 1 LAST PATH I107
J 0
(-2750 3050);
DISPLAY 0.978723 (-2750 3050);
DISPLAY INVISIBLE (-2750 3050);
FORCEPROP 2 LAST CDS_LIB pure_quanta
J 0
(-2800 2900);
DISPLAY INVISIBLE (-2800 2900);
FORCEADD VCC_CORE..1
(-1850 3200);
FORCEPROP 3 LASTPIN (-1850 3150) SIG_NAME PVDDCR_CPU0_P0\g
J 0
(-1840 3160);
DISPLAY 0.659574 (-1840 3160);
PAINT MONO (-1840 3160);
DISPLAY INVISIBLE (-1840 3160);
FORCEPROP 1 LAST HDL_POWER PVDDCR_CPU0_P0
J 1
(-1850 3250);
DISPLAY 0.489362 (-1850 3250);
PAINT GREEN (-1850 3250);
FORCEPROP 2 LAST CDS_LIB pure_quanta_power
J 0
(-1850 3200);
DISPLAY INVISIBLE (-1850 3200);
FORCEPROP 1 LAST PATH I109
J 0
(-1800 3225);
DISPLAY 0.872340 (-1800 3225);
PAINT AQUA (-1800 3225);
DISPLAY INVISIBLE (-1800 3225);
FORCEADD Q_RES..1
(-7325 4150);
FORCEPROP 1 LAST LOCATION PR320
J 0
(-7350 4200);
DISPLAY 0.489362 (-7350 4200);
PAINT SKYBLUE (-7350 4200);
FORCEPROP 0 LAST $SEC 1
J 0
(-7325 4225);
DISPLAY 0.680851 (-7325 4225);
PAINT MONO (-7325 4225);
DISPLAY INVISIBLE (-7325 4225);
FORCEPROP 0 LAST CDS_SEC 1
J 0
(-7325 4225);
DISPLAY 1.021277 (-7325 4225);
DISPLAY INVISIBLE (-7325 4225);
FORCEPROP 1 LASTPIN (-7425 4150) $PN 1
J 0
(-7413 4162);
DISPLAY 0.489362 (-7413 4162);
PAINT MONO (-7413 4162);
FORCEPROP 1 LASTPIN (-7225 4150) $PN 2
J 0
(-7263 4162);
DISPLAY 0.489362 (-7263 4162);
PAINT MONO (-7263 4162);
FORCEPROP 1 LAST PART_NUMBER CS28872FB01
J 0
(-7600 4100);
DISPLAY 0.489362 (-7600 4100);
PAINT SKYBLUE (-7600 4100);
FORCEPROP 1 LAST MATERIAL EMPTY
J 0
(-7625 4050);
DISPLAY 0.489362 (-7625 4050);
PAINT RED (-7625 4050);
FORCEPROP 1 LAST WATTAGE 1/16W
J 0
(-7225 4050);
DISPLAY 0.489362 (-7225 4050);
PAINT SKYBLUE (-7225 4050);
FORCEPROP 1 LAST TOLERANCE 1%
J 0
(-7200 4175);
DISPLAY 0.489362 (-7200 4175);
PAINT SKYBLUE (-7200 4175);
FORCEPROP 1 LAST VALUE 8.87K
J 2
(-7425 4175);
DISPLAY 0.489362 (-7425 4175);
PAINT SKYBLUE (-7425 4175);
FORCEPROP 1 LAST PACK_TYPE 0402LF
J 0
(-7225 4100);
DISPLAY 0.489362 (-7225 4100);
PAINT SKYBLUE (-7225 4100);
FORCEPROP 2 LAST CDS_LIB pure_quanta
J 0
(-7325 4150);
DISPLAY INVISIBLE (-7325 4150);
FORCEPROP 1 LAST PATH I11
J 0
(-7375 4300);
DISPLAY 0.978723 (-7375 4300);
PAINT WHITE (-7375 4300);
DISPLAY INVISIBLE (-7375 4300);
FORCEADD UNIVERSAL_GND..1
(-1850 2525);
FORCEPROP 3 LASTPIN (-1850 2575) SIG_NAME GND\g
J 0
(-1840 2585);
DISPLAY 0.659574 (-1840 2585);
PAINT MONO (-1840 2585);
DISPLAY INVISIBLE (-1840 2585);
FORCEPROP 2 LAST CDS_LIB pure_quanta_power
J 0
(-1850 2525);
DISPLAY INVISIBLE (-1850 2525);
FORCEPROP 1 LAST PATH I110
J 0
(-1775 2525);
DISPLAY 0.872340 (-1775 2525);
PAINT AQUA (-1775 2525);
DISPLAY INVISIBLE (-1775 2525);
FORCEPROP 1 LAST HDL_POWER GND
J 1
(-1825 2450);
DISPLAY 0.872340 (-1825 2450);
PAINT GREEN (-1825 2450);
DISPLAY INVISIBLE (-1825 2450);
FORCEADD Q_CAPP..1
(-1875 2900);
FORCEPROP 1 LAST LOCATION PC498
J 0
(-1825 3000);
DISPLAY 0.489362 (-1825 3000);
PAINT SKYBLUE (-1825 3000);
FORCEPROP 0 LAST $SEC 1
J 0
(-1825 3050);
DISPLAY 0.680851 (-1825 3050);
PAINT MONO (-1825 3050);
DISPLAY INVISIBLE (-1825 3050);
FORCEPROP 0 LAST CDS_SEC 1
J 0
(-1825 3050);
DISPLAY 1.021277 (-1825 3050);
DISPLAY INVISIBLE (-1825 3050);
FORCEPROP 1 LASTPIN (-1875 3000) $PN 1
J 0
(-1865 2985);
DISPLAY 0.489362 (-1865 2985);
PAINT MONO (-1865 2985);
FORCEPROP 1 LASTPIN (-1875 2800) $PN 2
J 0
(-1865 2785);
DISPLAY 0.489362 (-1865 2785);
PAINT MONO (-1865 2785);
FORCEPROP 1 LAST PACK_TYPE SMLF
J 0
(-1825 2750);
DISPLAY 0.489362 (-1825 2750);
PAINT SKYBLUE (-1825 2750);
FORCEPROP 1 LAST VOLTAGE 4V
J 0
(-1825 2850);
DISPLAY 0.489362 (-1825 2850);
PAINT SKYBLUE (-1825 2850);
FORCEPROP 1 LAST VALUE 220UF
J 0
(-1825 2950);
DISPLAY 0.489362 (-1825 2950);
PAINT SKYBLUE (-1825 2950);
FORCEPROP 1 LAST TOLERANCE 20%
J 0
(-1825 2900);
DISPLAY 0.489362 (-1825 2900);
PAINT SKYBLUE (-1825 2900);
FORCEPROP 1 LAST PART_NUMBER CH122KM8801
J 0
(-1825 2700);
DISPLAY 0.489362 (-1825 2700);
PAINT SKYBLUE (-1825 2700);
FORCEPROP 1 LAST MATERIAL SPCAP
J 0
(-1825 2800);
DISPLAY 0.489362 (-1825 2800);
PAINT SKYBLUE (-1825 2800);
FORCEPROP 1 LAST PATH I112
J 0
(-1825 3050);
DISPLAY 0.978723 (-1825 3050);
DISPLAY INVISIBLE (-1825 3050);
FORCEPROP 2 LAST CDS_LIB pure_quanta
J 0
(-1875 2900);
DISPLAY INVISIBLE (-1875 2900);
FORCEADD Q_CAP..1
(-5525 5325);
FORCEPROP 1 LAST LOCATION PC479_1
J 0
(-5475 5425);
DISPLAY 0.489362 (-5475 5425);
PAINT SKYBLUE (-5475 5425);
FORCEPROP 0 LAST $SEC 1
J 0
(-5475 5450);
DISPLAY 0.680851 (-5475 5450);
PAINT MONO (-5475 5450);
DISPLAY INVISIBLE (-5475 5450);
FORCEPROP 0 LAST CDS_SEC 1
J 0
(-5475 5450);
DISPLAY 1.021277 (-5475 5450);
DISPLAY INVISIBLE (-5475 5450);
FORCEPROP 1 LASTPIN (-5525 5425) $PN 1
J 0
(-5515 5405);
DISPLAY 0.489362 (-5515 5405);
PAINT MONO (-5515 5405);
FORCEPROP 1 LASTPIN (-5525 5225) $PN 2
J 0
(-5515 5205);
DISPLAY 0.489362 (-5515 5205);
PAINT MONO (-5515 5205);
FORCEPROP 1 LAST PART_NUMBER CH4104K1B00
J 0
(-5475 5175);
DISPLAY 0.489362 (-5475 5175);
PAINT SKYBLUE (-5475 5175);
FORCEPROP 1 LAST MATERIAL X7R
J 0
(-5475 5225);
DISPLAY 0.489362 (-5475 5225);
PAINT SKYBLUE (-5475 5225);
FORCEPROP 1 LAST TOLERANCE 10%
J 0
(-5475 5275);
DISPLAY 0.489362 (-5475 5275);
PAINT SKYBLUE (-5475 5275);
FORCEPROP 1 LAST VALUE 0.1UF
J 0
(-5475 5375);
DISPLAY 0.489362 (-5475 5375);
PAINT SKYBLUE (-5475 5375);
FORCEPROP 1 LAST VOLTAGE 25V
J 0
(-5475 5325);
DISPLAY 0.489362 (-5475 5325);
PAINT SKYBLUE (-5475 5325);
FORCEPROP 1 LAST PACK_TYPE 0402
J 0
(-5475 5125);
DISPLAY 0.489362 (-5475 5125);
PAINT SKYBLUE (-5475 5125);
FORCEPROP 2 LAST CDS_LIB pure_quanta
J 0
(-5525 5325);
DISPLAY INVISIBLE (-5525 5325);
FORCEPROP 1 LAST PATH I113
J 0
(-5475 5475);
DISPLAY 0.978723 (-5475 5475);
PAINT WHITE (-5475 5475);
DISPLAY INVISIBLE (-5475 5475);
FORCEADD Q_CAP..1
(-5525 2575);
FORCEPROP 1 LAST LOCATION PC480_2
J 0
(-5475 2675);
DISPLAY 0.489362 (-5475 2675);
PAINT SKYBLUE (-5475 2675);
FORCEPROP 0 LAST $SEC 1
J 0
(-5475 2725);
DISPLAY 0.680851 (-5475 2725);
PAINT MONO (-5475 2725);
DISPLAY INVISIBLE (-5475 2725);
FORCEPROP 0 LAST CDS_SEC 1
J 0
(-5475 2725);
DISPLAY 1.021277 (-5475 2725);
DISPLAY INVISIBLE (-5475 2725);
FORCEPROP 1 LASTPIN (-5525 2675) $PN 1
J 0
(-5515 2655);
DISPLAY 0.489362 (-5515 2655);
PAINT MONO (-5515 2655);
FORCEPROP 1 LASTPIN (-5525 2475) $PN 2
J 0
(-5515 2455);
DISPLAY 0.489362 (-5515 2455);
PAINT MONO (-5515 2455);
FORCEPROP 1 LAST MATERIAL X7R
J 0
(-5475 2475);
DISPLAY 0.489362 (-5475 2475);
PAINT SKYBLUE (-5475 2475);
FORCEPROP 1 LAST PART_NUMBER CH4104K1B00
J 0
(-5475 2425);
DISPLAY 0.489362 (-5475 2425);
PAINT SKYBLUE (-5475 2425);
FORCEPROP 1 LAST VALUE 0.1UF
J 0
(-5475 2625);
DISPLAY 0.489362 (-5475 2625);
PAINT SKYBLUE (-5475 2625);
FORCEPROP 1 LAST TOLERANCE 10%
J 0
(-5475 2525);
DISPLAY 0.489362 (-5475 2525);
PAINT SKYBLUE (-5475 2525);
FORCEPROP 1 LAST VOLTAGE 25V
J 0
(-5475 2575);
DISPLAY 0.489362 (-5475 2575);
PAINT SKYBLUE (-5475 2575);
FORCEPROP 1 LAST PACK_TYPE 0402
J 0
(-5475 2375);
DISPLAY 0.489362 (-5475 2375);
PAINT SKYBLUE (-5475 2375);
FORCEPROP 2 LAST CDS_LIB pure_quanta
J 0
(-5525 2575);
DISPLAY INVISIBLE (-5525 2575);
FORCEPROP 1 LAST PATH I114
J 0
(-5475 2725);
DISPLAY 0.978723 (-5475 2725);
PAINT WHITE (-5475 2725);
DISPLAY INVISIBLE (-5475 2725);
FORCEADD Q_CAP..1
(-7625 2050);
FORCEPROP 1 LAST LOCATION PC476
J 0
(-7575 2150);
DISPLAY 0.489362 (-7575 2150);
PAINT SKYBLUE (-7575 2150);
FORCEPROP 0 LAST $SEC 1
J 0
(-7575 2200);
DISPLAY 0.680851 (-7575 2200);
PAINT MONO (-7575 2200);
DISPLAY INVISIBLE (-7575 2200);
FORCEPROP 0 LAST CDS_SEC 1
J 0
(-7575 2200);
DISPLAY 1.021277 (-7575 2200);
DISPLAY INVISIBLE (-7575 2200);
FORCEPROP 1 LASTPIN (-7625 2150) $PN 1
J 0
(-7615 2130);
DISPLAY 0.489362 (-7615 2130);
PAINT MONO (-7615 2130);
FORCEPROP 1 LASTPIN (-7625 1950) $PN 2
J 0
(-7615 1930);
DISPLAY 0.489362 (-7615 1930);
PAINT MONO (-7615 1930);
FORCEPROP 1 LAST MATERIAL X6S
J 0
(-7575 1950);
DISPLAY 0.489362 (-7575 1950);
PAINT SKYBLUE (-7575 1950);
FORCEPROP 1 LAST TOLERANCE 10%
J 0
(-7575 2000);
DISPLAY 0.489362 (-7575 2000);
PAINT SKYBLUE (-7575 2000);
FORCEPROP 1 LAST VALUE 2.2UF
J 0
(-7575 2100);
DISPLAY 0.489362 (-7575 2100);
PAINT SKYBLUE (-7575 2100);
FORCEPROP 1 LAST PART_NUMBER CH5222KEB01
J 0
(-7575 1900);
DISPLAY 0.489362 (-7575 1900);
PAINT SKYBLUE (-7575 1900);
FORCEPROP 1 LAST VOLTAGE 10V
J 0
(-7575 2050);
DISPLAY 0.489362 (-7575 2050);
PAINT SKYBLUE (-7575 2050);
FORCEPROP 1 LAST PACK_TYPE C0402
J 0
(-7575 1850);
DISPLAY 0.489362 (-7575 1850);
PAINT SKYBLUE (-7575 1850);
FORCEPROP 2 LAST CDS_LIB pure_quanta
J 0
(-7625 2050);
DISPLAY INVISIBLE (-7625 2050);
FORCEPROP 1 LAST PATH I115
J 0
(-7575 2200);
DISPLAY 0.978723 (-7575 2200);
PAINT WHITE (-7575 2200);
DISPLAY INVISIBLE (-7575 2200);
FORCEADD UNIVERSAL_GND..1
(-7625 1850);
FORCEPROP 3 LASTPIN (-7625 1900) SIG_NAME GND\g
J 0
(-7615 1910);
DISPLAY 0.659574 (-7615 1910);
PAINT MONO (-7615 1910);
DISPLAY INVISIBLE (-7615 1910);
FORCEPROP 2 LAST CDS_LIB pure_quanta_power
J 0
(-7625 1850);
DISPLAY INVISIBLE (-7625 1850);
FORCEPROP 1 LAST PATH I116
J 0
(-7550 1850);
DISPLAY 0.872340 (-7550 1850);
PAINT AQUA (-7550 1850);
DISPLAY INVISIBLE (-7550 1850);
FORCEPROP 1 LAST HDL_POWER GND
J 1
(-7600 1775);
DISPLAY 0.872340 (-7600 1775);
PAINT GREEN (-7600 1775);
DISPLAY INVISIBLE (-7600 1775);
FORCEADD UNIVERSAL_GND..1
(-7275 2300);
FORCEPROP 3 LASTPIN (-7275 2350) SIG_NAME GND\g
J 0
(-7265 2360);
DISPLAY 0.659574 (-7265 2360);
PAINT MONO (-7265 2360);
DISPLAY INVISIBLE (-7265 2360);
FORCEPROP 2 LAST CDS_LIB pure_quanta_power
J 0
(-7275 2300);
DISPLAY INVISIBLE (-7275 2300);
FORCEPROP 1 LAST PATH I117
J 0
(-7200 2300);
DISPLAY 0.872340 (-7200 2300);
PAINT AQUA (-7200 2300);
DISPLAY INVISIBLE (-7200 2300);
FORCEPROP 1 LAST HDL_POWER GND
J 1
(-7250 2225);
DISPLAY 0.872340 (-7250 2225);
PAINT GREEN (-7250 2225);
DISPLAY INVISIBLE (-7250 2225);
FORCEADD Q_RES..2
(-7625 2550);
FORCEPROP 1 LAST LOCATION PR319
J 0
(-7580 2675);
DISPLAY 0.489362 (-7580 2675);
PAINT SKYBLUE (-7580 2675);
FORCEPROP 0 LAST $SEC 1
J 0
(-7575 2725);
DISPLAY 0.680851 (-7575 2725);
PAINT MONO (-7575 2725);
DISPLAY INVISIBLE (-7575 2725);
FORCEPROP 0 LAST CDS_SEC 1
J 0
(-7575 2725);
DISPLAY 1.021277 (-7575 2725);
DISPLAY INVISIBLE (-7575 2725);
FORCEPROP 1 LASTPIN (-7625 2650) $PN 1
J 0
(-7620 2612);
DISPLAY 0.489362 (-7620 2612);
PAINT MONO (-7620 2612);
FORCEPROP 1 LASTPIN (-7625 2450) $PN 2
J 0
(-7620 2460);
DISPLAY 0.489362 (-7620 2460);
PAINT MONO (-7620 2460);
FORCEPROP 1 LAST WATTAGE 1/16W
J 0
(-7575 2525);
DISPLAY 0.489362 (-7575 2525);
PAINT SKYBLUE (-7575 2525);
FORCEPROP 1 LAST MATERIAL CHIP
J 0
(-7575 2475);
DISPLAY 0.489362 (-7575 2475);
PAINT SKYBLUE (-7575 2475);
FORCEPROP 1 LAST TOLERANCE 1%
J 0
(-7575 2575);
DISPLAY 0.489362 (-7575 2575);
PAINT SKYBLUE (-7575 2575);
FORCEPROP 1 LAST VALUE 2.2
J 0
(-7575 2625);
DISPLAY 0.489362 (-7575 2625);
PAINT SKYBLUE (-7575 2625);
FORCEPROP 1 LAST PART_NUMBER CS-2202FB00
J 0
(-7575 2425);
DISPLAY 0.489362 (-7575 2425);
PAINT SKYBLUE (-7575 2425);
FORCEPROP 1 LAST PACK_TYPE 0402LF
J 0
(-7575 2375);
DISPLAY 0.489362 (-7575 2375);
PAINT SKYBLUE (-7575 2375);
FORCEPROP 2 LAST CDS_LIB pure_quanta
J 0
(-7625 2550);
DISPLAY INVISIBLE (-7625 2550);
FORCEPROP 1 LAST PATH I118
J 0
(-7575 2725);
DISPLAY 0.978723 (-7575 2725);
PAINT WHITE (-7575 2725);
DISPLAY INVISIBLE (-7575 2725);
FORCEADD Q_CAP..1
(-7275 2575);
FORCEPROP 1 LAST LOCATION PC478_C0P0_2
J 0
(-7225 2675);
DISPLAY 0.489362 (-7225 2675);
PAINT SKYBLUE (-7225 2675);
FORCEPROP 0 LAST $SEC 1
J 0
(-7225 2725);
DISPLAY 0.680851 (-7225 2725);
PAINT MONO (-7225 2725);
DISPLAY INVISIBLE (-7225 2725);
FORCEPROP 0 LAST CDS_SEC 1
J 0
(-7225 2725);
DISPLAY 1.021277 (-7225 2725);
DISPLAY INVISIBLE (-7225 2725);
FORCEPROP 1 LASTPIN (-7275 2675) $PN 1
J 0
(-7265 2655);
DISPLAY 0.489362 (-7265 2655);
PAINT MONO (-7265 2655);
FORCEPROP 1 LASTPIN (-7275 2475) $PN 2
J 0
(-7265 2455);
DISPLAY 0.489362 (-7265 2455);
PAINT MONO (-7265 2455);
FORCEPROP 1 LAST MATERIAL X6S
J 0
(-7225 2475);
DISPLAY 0.489362 (-7225 2475);
PAINT SKYBLUE (-7225 2475);
FORCEPROP 1 LAST TOLERANCE 10%
J 0
(-7225 2525);
DISPLAY 0.489362 (-7225 2525);
PAINT SKYBLUE (-7225 2525);
FORCEPROP 1 LAST VALUE 2.2UF
J 0
(-7225 2625);
DISPLAY 0.489362 (-7225 2625);
PAINT SKYBLUE (-7225 2625);
FORCEPROP 1 LAST PART_NUMBER CH5222KEB01
J 0
(-7225 2425);
DISPLAY 0.489362 (-7225 2425);
PAINT SKYBLUE (-7225 2425);
FORCEPROP 1 LAST VOLTAGE 10V
J 0
(-7225 2575);
DISPLAY 0.489362 (-7225 2575);
PAINT SKYBLUE (-7225 2575);
FORCEPROP 1 LAST PACK_TYPE C0402
J 0
(-7225 2375);
DISPLAY 0.489362 (-7225 2375);
PAINT SKYBLUE (-7225 2375);
FORCEPROP 2 LAST CDS_LIB pure_quanta
J 0
(-7275 2575);
DISPLAY INVISIBLE (-7275 2575);
FORCEPROP 1 LAST PATH I119
J 0
(-7225 2725);
DISPLAY 0.978723 (-7225 2725);
PAINT WHITE (-7225 2725);
DISPLAY INVISIBLE (-7225 2725);
FORCEADD UNIVERSAL_GND..1
(-7650 3975);
FORCEPROP 3 LASTPIN (-7650 4025) SIG_NAME GND\g
J 0
(-7640 4035);
DISPLAY 0.659574 (-7640 4035);
PAINT MONO (-7640 4035);
DISPLAY INVISIBLE (-7640 4035);
FORCEPROP 2 LAST CDS_LIB pure_quanta_power
J 0
(-7650 3975);
DISPLAY INVISIBLE (-7650 3975);
FORCEPROP 1 LAST PATH I12
J 0
(-7575 3975);
DISPLAY 0.872340 (-7575 3975);
PAINT AQUA (-7575 3975);
DISPLAY INVISIBLE (-7575 3975);
FORCEPROP 1 LAST HDL_POWER GND
J 1
(-7625 3900);
DISPLAY 0.872340 (-7625 3900);
PAINT GREEN (-7625 3900);
DISPLAY INVISIBLE (-7625 3900);
FORCEADD VCC_CORE..1
(-7625 2950);
FORCEPROP 3 LASTPIN (-7625 2900) SIG_NAME PVDDCR_CPU0_P0_PVCC\g
J 0
(-7615 2910);
DISPLAY 0.659574 (-7615 2910);
PAINT MONO (-7615 2910);
DISPLAY INVISIBLE (-7615 2910);
FORCEPROP 1 LAST HDL_POWER PVDDCR_CPU0_P0_PVCC
J 1
(-7625 3000);
DISPLAY 0.489362 (-7625 3000);
PAINT GREEN (-7625 3000);
FORCEPROP 2 LAST CDS_LIB pure_quanta_power
J 0
(-7625 2950);
DISPLAY INVISIBLE (-7625 2950);
FORCEPROP 1 LAST PATH I120
J 0
(-7575 2975);
DISPLAY 0.872340 (-7575 2975);
PAINT AQUA (-7575 2975);
DISPLAY INVISIBLE (-7575 2975);
FORCEADD ISL99390FRZTR5935..1
(-6175 4450);
FORCEPROP 1 LAST LOCATION PU6
J 0
(-6475 5325);
DISPLAY 0.489362 (-6475 5325);
PAINT SKYBLUE (-6475 5325);
FORCEPROP 0 LAST $SEC 1
J 0
(-6475 5475);
DISPLAY 0.680851 (-6475 5475);
PAINT MONO (-6475 5475);
DISPLAY INVISIBLE (-6475 5475);
FORCEPROP 0 LAST CDS_SEC 1
J 0
(-6475 5475);
DISPLAY 1.021277 (-6475 5475);
DISPLAY INVISIBLE (-6475 5475);
FORCEPROP 0 LASTPIN (-5775 4000) $PN 2
J 0
(-5765 4010);
DISPLAY 0.489362 (-5765 4010);
PAINT MONO (-5765 4010);
FORCEPROP 0 LASTPIN (-5775 4800) $PN 33
J 0
(-5765 4810);
DISPLAY 0.489362 (-5765 4810);
PAINT MONO (-5765 4810);
FORCEPROP 0 LASTPIN (-6625 4200) $PN 31
J 2
(-6635 4210);
DISPLAY 0.489362 (-6635 4210);
PAINT MONO (-6635 4210);
FORCEPROP 0 LASTPIN (-6625 4600) $PN 35
J 2
(-6635 4610);
DISPLAY 0.489362 (-6635 4610);
PAINT MONO (-6635 4610);
FORCEPROP 0 LASTPIN (-5775 4150) $PN 6
J 0
(-5765 4160);
DISPLAY 0.489362 (-5765 4160);
PAINT MONO (-5765 4160);
FORCEPROP 0 LASTPIN (-5775 4100) $PN 41
J 0
(-5765 4110);
DISPLAY 0.489362 (-5765 4110);
PAINT MONO (-5765 4110);
FORCEPROP 0 LASTPIN (-6625 4450) $PN 38
J 2
(-6635 4460);
DISPLAY 0.489362 (-6635 4460);
PAINT MONO (-6635 4460);
FORCEPROP 0 LASTPIN (-6625 4150) $PN 37
J 2
(-6635 4160);
DISPLAY 0.489362 (-6635 4160);
PAINT MONO (-6635 4160);
FORCEPROP 0 LASTPIN (-5775 3950) $PN 5
J 0
(-5765 3960);
DISPLAY 0.489362 (-5765 3960);
PAINT MONO (-5765 3960);
FORCEPROP 0 LASTPIN (-5775 3900) $PN 7_9-20_24
J 0
(-5765 3910);
DISPLAY 0.489362 (-5765 3910);
PAINT MONO (-5765 3910);
FORCEPROP 0 LASTPIN (-5775 3850) $PN 40
J 0
(-5765 3860);
DISPLAY 0.489362 (-5765 3860);
PAINT MONO (-5765 3860);
FORCEPROP 0 LASTPIN (-5775 4550) $PN 32
J 0
(-5765 4560);
DISPLAY 0.489362 (-5765 4560);
PAINT MONO (-5765 4560);
FORCEPROP 0 LASTPIN (-6625 5100) $PN 4
J 2
(-6635 5110);
DISPLAY 0.489362 (-6635 5110);
PAINT MONO (-6635 5110);
FORCEPROP 0 LASTPIN (-6625 3850) $PN 34
J 2
(-6635 3860);
DISPLAY 0.489362 (-6635 3860);
PAINT MONO (-6635 3860);
FORCEPROP 0 LASTPIN (-6625 4350) $PN 39
J 2
(-6635 4360);
DISPLAY 0.489362 (-6635 4360);
PAINT MONO (-6635 4360);
FORCEPROP 0 LASTPIN (-5775 4450) $PN 10_19
J 0
(-5765 4460);
DISPLAY 0.489362 (-5765 4460);
PAINT MONO (-5765 4460);
FORCEPROP 0 LASTPIN (-6625 3950) $PN 36
J 2
(-6635 3960);
DISPLAY 0.489362 (-6635 3960);
PAINT MONO (-6635 3960);
FORCEPROP 0 LASTPIN (-6625 4800) $PN 3
J 2
(-6635 4810);
DISPLAY 0.489362 (-6635 4810);
PAINT MONO (-6635 4810);
FORCEPROP 0 LASTPIN (-5775 5100) $PN 25_29
J 0
(-5765 5110);
DISPLAY 0.489362 (-5765 5110);
PAINT MONO (-5765 5110);
FORCEPROP 0 LASTPIN (-5775 5050) $PN 30
J 0
(-5765 5060);
DISPLAY 0.489362 (-5765 5060);
PAINT MONO (-5765 5060);
FORCEPROP 0 LASTPIN (-5775 4200) $PN 1
J 0
(-5765 4210);
DISPLAY 0.489362 (-5765 4210);
PAINT MONO (-5765 4210);
FORCEPROP 2 LAST PART_TYPE SMLF
J 0
(-6475 5425);
DISPLAY 1.021277 (-6475 5425);
FORCEPROP 1 LAST MATERIAL IC
J 0
(-6475 5175);
DISPLAY 0.489362 (-6475 5175);
PAINT SKYBLUE (-6475 5175);
FORCEPROP 2 LAST VALUE ISL99390FRZ-TR5935
J 0
(-6475 5375);
DISPLAY 0.489362 (-6475 5375);
PAINT SKYBLUE (-6475 5375);
FORCEPROP 1 LAST PART_NUMBER AL099390004
J 0
(-6475 5250);
DISPLAY 0.489362 (-6475 5250);
PAINT SKYBLUE (-6475 5250);
FORCEPROP 1 LAST CDS_LMAN_SYM_OUTLINE -300,700,250,-650
J 0
(-6175 4450);
DISPLAY 0.468085 (-6175 4450);
PAINT GREEN (-6175 4450);
DISPLAY INVISIBLE (-6175 4450);
FORCEPROP 2 LAST CDS_LIB pure_quanta
J 0
(-6175 4450);
DISPLAY INVISIBLE (-6175 4450);
FORCEPROP 1 LAST NEEDS_NO_SIZE TRUE
J 0
(-6175 4450);
DISPLAY 0.723404 (-6175 4450);
PAINT GREEN (-6175 4450);
DISPLAY INVISIBLE (-6175 4450);
FORCEPROP 1 LAST PATH I121
J 0
(-6175 4450);
DISPLAY 0.723404 (-6175 4450);
PAINT GREEN (-6175 4450);
DISPLAY INVISIBLE (-6175 4450);
FORCEADD ISL99390FRZTR5935..1
(-6150 1700);
FORCEPROP 1 LAST LOCATION PU43
J 0
(-6450 2575);
DISPLAY 0.489362 (-6450 2575);
PAINT SKYBLUE (-6450 2575);
FORCEPROP 0 LAST $SEC 1
J 0
(-6450 2725);
DISPLAY 0.680851 (-6450 2725);
PAINT MONO (-6450 2725);
DISPLAY INVISIBLE (-6450 2725);
FORCEPROP 0 LAST CDS_SEC 1
J 0
(-6450 2725);
DISPLAY 1.021277 (-6450 2725);
DISPLAY INVISIBLE (-6450 2725);
FORCEPROP 0 LASTPIN (-5750 1250) $PN 2
J 0
(-5740 1260);
DISPLAY 0.489362 (-5740 1260);
PAINT MONO (-5740 1260);
FORCEPROP 0 LASTPIN (-5750 2050) $PN 33
J 0
(-5740 2060);
DISPLAY 0.489362 (-5740 2060);
PAINT MONO (-5740 2060);
FORCEPROP 0 LASTPIN (-6600 1450) $PN 31
J 2
(-6610 1460);
DISPLAY 0.489362 (-6610 1460);
PAINT MONO (-6610 1460);
FORCEPROP 0 LASTPIN (-6600 1850) $PN 35
J 2
(-6610 1860);
DISPLAY 0.489362 (-6610 1860);
PAINT MONO (-6610 1860);
FORCEPROP 0 LASTPIN (-5750 1400) $PN 6
J 0
(-5740 1410);
DISPLAY 0.489362 (-5740 1410);
PAINT MONO (-5740 1410);
FORCEPROP 0 LASTPIN (-5750 1350) $PN 41
J 0
(-5740 1360);
DISPLAY 0.489362 (-5740 1360);
PAINT MONO (-5740 1360);
FORCEPROP 0 LASTPIN (-6600 1700) $PN 38
J 2
(-6610 1710);
DISPLAY 0.489362 (-6610 1710);
PAINT MONO (-6610 1710);
FORCEPROP 0 LASTPIN (-6600 1400) $PN 37
J 2
(-6610 1410);
DISPLAY 0.489362 (-6610 1410);
PAINT MONO (-6610 1410);
FORCEPROP 0 LASTPIN (-5750 1200) $PN 5
J 0
(-5740 1210);
DISPLAY 0.489362 (-5740 1210);
PAINT MONO (-5740 1210);
FORCEPROP 0 LASTPIN (-5750 1150) $PN 7_9-20_24
J 0
(-5740 1160);
DISPLAY 0.489362 (-5740 1160);
PAINT MONO (-5740 1160);
FORCEPROP 0 LASTPIN (-5750 1100) $PN 40
J 0
(-5740 1110);
DISPLAY 0.489362 (-5740 1110);
PAINT MONO (-5740 1110);
FORCEPROP 0 LASTPIN (-5750 1800) $PN 32
J 0
(-5740 1810);
DISPLAY 0.489362 (-5740 1810);
PAINT MONO (-5740 1810);
FORCEPROP 0 LASTPIN (-6600 2350) $PN 4
J 2
(-6610 2360);
DISPLAY 0.489362 (-6610 2360);
PAINT MONO (-6610 2360);
FORCEPROP 0 LASTPIN (-6600 1100) $PN 34
J 2
(-6610 1110);
DISPLAY 0.489362 (-6610 1110);
PAINT MONO (-6610 1110);
FORCEPROP 0 LASTPIN (-6600 1600) $PN 39
J 2
(-6610 1610);
DISPLAY 0.489362 (-6610 1610);
PAINT MONO (-6610 1610);
FORCEPROP 0 LASTPIN (-5750 1700) $PN 10_19
J 0
(-5740 1710);
DISPLAY 0.489362 (-5740 1710);
PAINT MONO (-5740 1710);
FORCEPROP 0 LASTPIN (-6600 1200) $PN 36
J 2
(-6610 1210);
DISPLAY 0.489362 (-6610 1210);
PAINT MONO (-6610 1210);
FORCEPROP 0 LASTPIN (-6600 2050) $PN 3
J 2
(-6610 2060);
DISPLAY 0.489362 (-6610 2060);
PAINT MONO (-6610 2060);
FORCEPROP 0 LASTPIN (-5750 2350) $PN 25_29
J 0
(-5740 2360);
DISPLAY 0.489362 (-5740 2360);
PAINT MONO (-5740 2360);
FORCEPROP 0 LASTPIN (-5750 2300) $PN 30
J 0
(-5740 2310);
DISPLAY 0.489362 (-5740 2310);
PAINT MONO (-5740 2310);
FORCEPROP 0 LASTPIN (-5750 1450) $PN 1
J 0
(-5740 1460);
DISPLAY 0.489362 (-5740 1460);
PAINT MONO (-5740 1460);
FORCEPROP 2 LAST PART_TYPE SMLF
J 0
(-6450 2675);
DISPLAY 1.021277 (-6450 2675);
FORCEPROP 1 LAST MATERIAL IC
J 0
(-6450 2425);
DISPLAY 0.489362 (-6450 2425);
PAINT SKYBLUE (-6450 2425);
FORCEPROP 2 LAST VALUE ISL99390FRZ-TR5935
J 0
(-6450 2625);
DISPLAY 0.489362 (-6450 2625);
PAINT SKYBLUE (-6450 2625);
FORCEPROP 1 LAST PART_NUMBER AL099390004
J 0
(-6450 2500);
DISPLAY 0.489362 (-6450 2500);
PAINT SKYBLUE (-6450 2500);
FORCEPROP 1 LAST NEEDS_NO_SIZE TRUE
J 0
(-6150 1700);
DISPLAY 0.723404 (-6150 1700);
PAINT GREEN (-6150 1700);
DISPLAY INVISIBLE (-6150 1700);
FORCEPROP 2 LAST CDS_LIB pure_quanta
J 0
(-6150 1700);
DISPLAY INVISIBLE (-6150 1700);
FORCEPROP 1 LAST CDS_LMAN_SYM_OUTLINE -300,700,250,-650
J 0
(-6150 1700);
DISPLAY 0.468085 (-6150 1700);
PAINT GREEN (-6150 1700);
DISPLAY INVISIBLE (-6150 1700);
FORCEPROP 1 LAST PATH I122
J 0
(-6150 1700);
DISPLAY 0.723404 (-6150 1700);
PAINT GREEN (-6150 1700);
DISPLAY INVISIBLE (-6150 1700);
FORCEADD Q_CAPP..1
(-3150 2900);
FORCEPROP 1 LAST LOCATION PC108
J 0
(-3100 3000);
DISPLAY 0.489362 (-3100 3000);
PAINT SKYBLUE (-3100 3000);
FORCEPROP 0 LAST $SEC 1
J 0
(-3100 3025);
DISPLAY 0.680851 (-3100 3025);
PAINT MONO (-3100 3025);
DISPLAY INVISIBLE (-3100 3025);
FORCEPROP 0 LAST CDS_SEC 1
J 0
(-3100 3025);
DISPLAY 1.021277 (-3100 3025);
DISPLAY INVISIBLE (-3100 3025);
FORCEPROP 1 LASTPIN (-3150 3000) $PN 1
J 0
(-3140 2985);
DISPLAY 0.489362 (-3140 2985);
PAINT MONO (-3140 2985);
FORCEPROP 1 LASTPIN (-3150 2800) $PN 2
J 0
(-3140 2785);
DISPLAY 0.489362 (-3140 2785);
PAINT MONO (-3140 2785);
FORCEPROP 1 LAST VOLTAGE 4V
J 0
(-3100 2850);
DISPLAY 0.489362 (-3100 2850);
PAINT SKYBLUE (-3100 2850);
FORCEPROP 1 LAST PACK_TYPE SMLF
J 0
(-3100 2750);
DISPLAY 0.489362 (-3100 2750);
PAINT SKYBLUE (-3100 2750);
FORCEPROP 1 LAST TOLERANCE 20%
J 0
(-3100 2900);
DISPLAY 0.489362 (-3100 2900);
PAINT SKYBLUE (-3100 2900);
FORCEPROP 1 LAST MATERIAL SPCAP
J 0
(-3100 2800);
DISPLAY 0.489362 (-3100 2800);
PAINT SKYBLUE (-3100 2800);
FORCEPROP 1 LAST PART_NUMBER CH122KM8801
J 0
(-3100 2700);
DISPLAY 0.489362 (-3100 2700);
PAINT SKYBLUE (-3100 2700);
FORCEPROP 1 LAST VALUE 220UF
J 0
(-3100 2950);
DISPLAY 0.489362 (-3100 2950);
PAINT SKYBLUE (-3100 2950);
FORCEPROP 2 LAST CDS_LIB pure_quanta
J 0
(-3150 2900);
DISPLAY INVISIBLE (-3150 2900);
FORCEPROP 1 LAST PATH I123
J 0
(-3100 3050);
DISPLAY 0.978723 (-3100 3050);
DISPLAY INVISIBLE (-3100 3050);
FORCEADD OFFPAGE..3
(-2150 1450);
FORCEPROP 2 LAST $XR0 171 
J 0
(-1876 1450);
DISPLAY 0.638298 (-1876 1450);
PAINT MONO (-1876 1450);
FORCEPROP 2 LAST CDS_LIB standard
J 0
(-2150 1450);
DISPLAY INVISIBLE (-2150 1450);
FORCEPROP 1 LAST COMMENT_BODY TRUE
J 0
(-2200 1350);
DISPLAY 0.872340 (-2200 1350);
PAINT GREEN (-2200 1350);
DISPLAY INVISIBLE (-2200 1350);
FORCEPROP 1 LAST OFFPAGE TRUE
J 0
(-1825 1325);
DISPLAY 0.872340 (-1825 1325);
PAINT GREEN (-1825 1325);
DISPLAY INVISIBLE (-1825 1325);
FORCEPROP 2 LAST PATH I124
J 0
(-1950 1525);
DISPLAY 1.021277 (-1950 1525);
DISPLAY INVISIBLE (-1950 1525);
FORCEADD Q_CAP..1
(-4800 4275);
FORCEPROP 1 LAST LOCATION PC178
J 0
(-4750 4375);
DISPLAY 0.489362 (-4750 4375);
PAINT SKYBLUE (-4750 4375);
FORCEPROP 0 LAST $SEC 1
J 0
(-4750 4400);
DISPLAY 0.680851 (-4750 4400);
PAINT MONO (-4750 4400);
DISPLAY INVISIBLE (-4750 4400);
FORCEPROP 0 LAST CDS_SEC 1
J 0
(-4750 4400);
DISPLAY 1.021277 (-4750 4400);
DISPLAY INVISIBLE (-4750 4400);
FORCEPROP 1 LASTPIN (-4800 4375) $PN 1
J 0
(-4790 4355);
DISPLAY 0.489362 (-4790 4355);
PAINT MONO (-4790 4355);
FORCEPROP 1 LASTPIN (-4800 4175) $PN 2
J 0
(-4790 4155);
DISPLAY 0.489362 (-4790 4155);
PAINT MONO (-4790 4155);
FORCEPROP 1 LAST MATERIAL EMPTY
J 0
(-4750 4175);
DISPLAY 0.489362 (-4750 4175);
PAINT RED (-4750 4175);
FORCEPROP 1 LAST TOLERANCE 10%
J 0
(-4750 4225);
DISPLAY 0.489362 (-4750 4225);
PAINT SKYBLUE (-4750 4225);
FORCEPROP 1 LAST VALUE 560PF
J 0
(-4750 4325);
DISPLAY 0.489362 (-4750 4325);
PAINT SKYBLUE (-4750 4325);
FORCEPROP 1 LAST PART_NUMBER CH1566K1B09
J 0
(-4750 4125);
DISPLAY 0.489362 (-4750 4125);
PAINT SKYBLUE (-4750 4125);
FORCEPROP 1 LAST VOLTAGE 50V
J 0
(-4750 4275);
DISPLAY 0.489362 (-4750 4275);
PAINT SKYBLUE (-4750 4275);
FORCEPROP 1 LAST PACK_TYPE C0402
J 0
(-4750 4075);
DISPLAY 0.489362 (-4750 4075);
PAINT SKYBLUE (-4750 4075);
FORCEPROP 2 LAST CDS_LIB pure_quanta
J 0
(-4800 4275);
DISPLAY INVISIBLE (-4800 4275);
FORCEPROP 1 LAST PATH I125
J 0
(-4750 4425);
DISPLAY 0.978723 (-4750 4425);
PAINT WHITE (-4750 4425);
DISPLAY INVISIBLE (-4750 4425);
FORCEADD Q_RES..2
(-4800 3825);
FORCEPROP 1 LAST LOCATION PR495
J 0
(-4755 3950);
DISPLAY 0.489362 (-4755 3950);
PAINT SKYBLUE (-4755 3950);
FORCEPROP 0 LAST $SEC 1
J 0
(-4750 3975);
DISPLAY 0.680851 (-4750 3975);
PAINT MONO (-4750 3975);
DISPLAY INVISIBLE (-4750 3975);
FORCEPROP 0 LAST CDS_SEC 1
J 0
(-4750 3975);
DISPLAY 1.021277 (-4750 3975);
DISPLAY INVISIBLE (-4750 3975);
FORCEPROP 1 LASTPIN (-4800 3925) $PN 1
J 0
(-4795 3887);
DISPLAY 0.489362 (-4795 3887);
PAINT MONO (-4795 3887);
FORCEPROP 1 LASTPIN (-4800 3725) $PN 2
J 0
(-4795 3735);
DISPLAY 0.489362 (-4795 3735);
PAINT MONO (-4795 3735);
FORCEPROP 1 LAST WATTAGE 1/8W
J 0
(-4760 3800);
DISPLAY 0.489362 (-4760 3800);
PAINT SKYBLUE (-4760 3800);
FORCEPROP 1 LAST MATERIAL EMPTY
J 0
(-4760 3750);
DISPLAY 0.489362 (-4760 3750);
PAINT RED (-4760 3750);
FORCEPROP 1 LAST TOLERANCE 1%
J 0
(-4755 3850);
DISPLAY 0.489362 (-4755 3850);
PAINT SKYBLUE (-4755 3850);
FORCEPROP 1 LAST VALUE 1.5
J 0
(-4755 3900);
DISPLAY 0.489362 (-4755 3900);
PAINT SKYBLUE (-4755 3900);
FORCEPROP 1 LAST PART_NUMBER CS-1504FB00
J 0
(-4760 3700);
DISPLAY 0.489362 (-4760 3700);
PAINT SKYBLUE (-4760 3700);
FORCEPROP 1 LAST PACK_TYPE 0402LF
J 0
(-4760 3650);
DISPLAY 0.489362 (-4760 3650);
PAINT SKYBLUE (-4760 3650);
FORCEPROP 2 LAST CDS_LIB pure_quanta
J 0
(-4800 3825);
DISPLAY INVISIBLE (-4800 3825);
FORCEPROP 1 LAST PATH I126
J 0
(-4750 4000);
DISPLAY 0.978723 (-4750 4000);
PAINT WHITE (-4750 4000);
DISPLAY INVISIBLE (-4750 4000);
FORCEADD UNIVERSAL_GND..1
(-4800 3600);
FORCEPROP 3 LASTPIN (-4800 3650) SIG_NAME GND\g
J 0
(-4790 3660);
DISPLAY 0.659574 (-4790 3660);
PAINT MONO (-4790 3660);
DISPLAY INVISIBLE (-4790 3660);
FORCEPROP 2 LAST CDS_LIB pure_quanta_power
J 0
(-4800 3600);
DISPLAY INVISIBLE (-4800 3600);
FORCEPROP 1 LAST PATH I127
J 0
(-4725 3600);
DISPLAY 0.872340 (-4725 3600);
PAINT AQUA (-4725 3600);
DISPLAY INVISIBLE (-4725 3600);
FORCEPROP 1 LAST HDL_POWER GND
J 1
(-4775 3525);
DISPLAY 0.872340 (-4775 3525);
PAINT GREEN (-4775 3525);
DISPLAY INVISIBLE (-4775 3525);
FORCEADD Q_CAP..1
(-4625 1525);
FORCEPROP 1 LAST LOCATION PC179
J 0
(-4575 1625);
DISPLAY 0.489362 (-4575 1625);
PAINT SKYBLUE (-4575 1625);
FORCEPROP 0 LAST $SEC 1
J 0
(-4575 1675);
DISPLAY 0.680851 (-4575 1675);
PAINT MONO (-4575 1675);
DISPLAY INVISIBLE (-4575 1675);
FORCEPROP 0 LAST CDS_SEC 1
J 0
(-4575 1675);
DISPLAY 1.021277 (-4575 1675);
DISPLAY INVISIBLE (-4575 1675);
FORCEPROP 1 LASTPIN (-4625 1625) $PN 1
J 0
(-4615 1605);
DISPLAY 0.489362 (-4615 1605);
PAINT MONO (-4615 1605);
FORCEPROP 1 LASTPIN (-4625 1425) $PN 2
J 0
(-4615 1405);
DISPLAY 0.489362 (-4615 1405);
PAINT MONO (-4615 1405);
FORCEPROP 1 LAST PACK_TYPE C0402
J 0
(-4575 1325);
DISPLAY 0.489362 (-4575 1325);
PAINT SKYBLUE (-4575 1325);
FORCEPROP 1 LAST MATERIAL EMPTY
J 0
(-4575 1425);
DISPLAY 0.489362 (-4575 1425);
PAINT RED (-4575 1425);
FORCEPROP 1 LAST TOLERANCE 10%
J 0
(-4575 1475);
DISPLAY 0.489362 (-4575 1475);
PAINT SKYBLUE (-4575 1475);
FORCEPROP 1 LAST VALUE 560PF
J 0
(-4575 1575);
DISPLAY 0.489362 (-4575 1575);
PAINT SKYBLUE (-4575 1575);
FORCEPROP 1 LAST PART_NUMBER CH1566K1B09
J 0
(-4575 1375);
DISPLAY 0.489362 (-4575 1375);
PAINT SKYBLUE (-4575 1375);
FORCEPROP 1 LAST VOLTAGE 50V
J 0
(-4575 1525);
DISPLAY 0.489362 (-4575 1525);
PAINT SKYBLUE (-4575 1525);
FORCEPROP 2 LAST CDS_LIB pure_quanta
J 0
(-4625 1525);
DISPLAY INVISIBLE (-4625 1525);
FORCEPROP 1 LAST PATH I128
J 0
(-4575 1675);
DISPLAY 0.978723 (-4575 1675);
PAINT WHITE (-4575 1675);
DISPLAY INVISIBLE (-4575 1675);
FORCEADD UNIVERSAL_GND..1
(-4625 850);
FORCEPROP 3 LASTPIN (-4625 900) SIG_NAME GND\g
J 0
(-4615 910);
DISPLAY 0.659574 (-4615 910);
PAINT MONO (-4615 910);
DISPLAY INVISIBLE (-4615 910);
FORCEPROP 2 LAST CDS_LIB pure_quanta_power
J 0
(-4625 850);
DISPLAY INVISIBLE (-4625 850);
FORCEPROP 1 LAST PATH I129
J 0
(-4550 850);
DISPLAY 0.872340 (-4550 850);
PAINT AQUA (-4550 850);
DISPLAY INVISIBLE (-4550 850);
FORCEPROP 1 LAST HDL_POWER GND
J 1
(-4600 775);
DISPLAY 0.872340 (-4600 775);
PAINT GREEN (-4600 775);
DISPLAY INVISIBLE (-4600 775);
FORCEADD Q_CAP..1
(-8000 4175);
FORCEPROP 1 LAST LOCATION PC473_1
J 0
(-7950 4275);
DISPLAY 0.489362 (-7950 4275);
PAINT SKYBLUE (-7950 4275);
FORCEPROP 0 LAST $SEC 1
J 0
(-7950 4300);
DISPLAY 0.680851 (-7950 4300);
PAINT MONO (-7950 4300);
DISPLAY INVISIBLE (-7950 4300);
FORCEPROP 0 LAST CDS_SEC 1
J 0
(-7950 4300);
DISPLAY 1.021277 (-7950 4300);
DISPLAY INVISIBLE (-7950 4300);
FORCEPROP 1 LASTPIN (-8000 4275) $PN 1
J 0
(-7990 4255);
DISPLAY 0.489362 (-7990 4255);
PAINT MONO (-7990 4255);
FORCEPROP 1 LASTPIN (-8000 4075) $PN 2
J 0
(-7990 4055);
DISPLAY 0.489362 (-7990 4055);
PAINT MONO (-7990 4055);
FORCEPROP 1 LAST MATERIAL X7R
J 0
(-7950 4075);
DISPLAY 0.489362 (-7950 4075);
PAINT SKYBLUE (-7950 4075);
FORCEPROP 1 LAST TOLERANCE 10%
J 0
(-7950 4125);
DISPLAY 0.489362 (-7950 4125);
PAINT SKYBLUE (-7950 4125);
FORCEPROP 1 LAST VALUE 0.1UF
J 0
(-7950 4225);
DISPLAY 0.489362 (-7950 4225);
PAINT SKYBLUE (-7950 4225);
FORCEPROP 1 LAST PART_NUMBER CH4104K1B00
J 0
(-7950 4025);
DISPLAY 0.489362 (-7950 4025);
PAINT SKYBLUE (-7950 4025);
FORCEPROP 1 LAST VOLTAGE 25V
J 0
(-7950 4175);
DISPLAY 0.489362 (-7950 4175);
PAINT SKYBLUE (-7950 4175);
FORCEPROP 1 LAST PACK_TYPE 0402
J 0
(-7950 3975);
DISPLAY 0.489362 (-7950 3975);
PAINT SKYBLUE (-7950 3975);
FORCEPROP 2 LAST CDS_LIB pure_quanta
J 0
(-8000 4175);
DISPLAY INVISIBLE (-8000 4175);
FORCEPROP 1 LAST PATH I13
J 0
(-7950 4325);
DISPLAY 0.978723 (-7950 4325);
PAINT WHITE (-7950 4325);
DISPLAY INVISIBLE (-7950 4325);
FORCEADD Q_RES..2
(-4625 1075);
FORCEPROP 1 LAST LOCATION PR496
J 0
(-4580 1200);
DISPLAY 0.489362 (-4580 1200);
PAINT SKYBLUE (-4580 1200);
FORCEPROP 0 LAST $SEC 1
J 0
(-4575 1250);
DISPLAY 0.680851 (-4575 1250);
PAINT MONO (-4575 1250);
DISPLAY INVISIBLE (-4575 1250);
FORCEPROP 0 LAST CDS_SEC 1
J 0
(-4575 1250);
DISPLAY 1.021277 (-4575 1250);
DISPLAY INVISIBLE (-4575 1250);
FORCEPROP 1 LASTPIN (-4625 1175) $PN 1
J 0
(-4620 1137);
DISPLAY 0.489362 (-4620 1137);
PAINT MONO (-4620 1137);
FORCEPROP 1 LASTPIN (-4625 975) $PN 2
J 0
(-4620 985);
DISPLAY 0.489362 (-4620 985);
PAINT MONO (-4620 985);
FORCEPROP 1 LAST WATTAGE 1/8W
J 0
(-4585 1050);
DISPLAY 0.489362 (-4585 1050);
PAINT SKYBLUE (-4585 1050);
FORCEPROP 1 LAST MATERIAL EMPTY
J 0
(-4585 1000);
DISPLAY 0.489362 (-4585 1000);
PAINT RED (-4585 1000);
FORCEPROP 1 LAST TOLERANCE 1%
J 0
(-4580 1100);
DISPLAY 0.489362 (-4580 1100);
PAINT SKYBLUE (-4580 1100);
FORCEPROP 1 LAST VALUE 1.5
J 0
(-4580 1150);
DISPLAY 0.489362 (-4580 1150);
PAINT SKYBLUE (-4580 1150);
FORCEPROP 1 LAST PART_NUMBER CS-1504FB00
J 0
(-4585 950);
DISPLAY 0.489362 (-4585 950);
PAINT SKYBLUE (-4585 950);
FORCEPROP 1 LAST PACK_TYPE 0402LF
J 0
(-4585 900);
DISPLAY 0.489362 (-4585 900);
PAINT SKYBLUE (-4585 900);
FORCEPROP 2 LAST CDS_LIB pure_quanta
J 0
(-4625 1075);
DISPLAY INVISIBLE (-4625 1075);
FORCEPROP 1 LAST PATH I130
J 0
(-4575 1250);
DISPLAY 0.978723 (-4575 1250);
PAINT WHITE (-4575 1250);
DISPLAY INVISIBLE (-4575 1250);
FORCEADD OFFPAGE..3
R 2
(-4325 4200);
FORCEPROP 2 LAST $XR0 172 
J 0
(-4779 4200);
DISPLAY 0.638298 (-4779 4200);
PAINT MONO (-4779 4200);
FORCEPROP 1 LAST OFFPAGE TRUE
J 2
(-4650 4075);
DISPLAY 0.872340 (-4650 4075);
PAINT GREEN (-4650 4075);
DISPLAY INVISIBLE (-4650 4075);
FORCEPROP 2 LAST CDS_LIB standard
J 0
(-4325 4200);
DISPLAY INVISIBLE (-4325 4200);
FORCEPROP 1 LAST COMMENT_BODY TRUE
J 2
(-4275 4100);
DISPLAY 0.872340 (-4275 4100);
PAINT GREEN (-4275 4100);
DISPLAY INVISIBLE (-4275 4100);
FORCEPROP 2 LAST PATH I131
J 0
(-4275 4275);
DISPLAY 1.021277 (-4275 4275);
DISPLAY INVISIBLE (-4275 4275);
FORCEADD Q_RES..1
R 1
(-8600 5725);
FORCEPROP 1 LAST LOCATION PR445
J 0
(-8575 5875);
DISPLAY 0.489362 (-8575 5875);
PAINT SKYBLUE (-8575 5875);
FORCEPROP 0 LAST $SEC 1
R 1
J 0
(-8575 5900);
DISPLAY 0.680851 (-8575 5900);
PAINT MONO (-8575 5900);
DISPLAY INVISIBLE (-8575 5900);
FORCEPROP 0 LAST CDS_SEC 1
R 1
J 0
(-8575 5900);
DISPLAY 1.021277 (-8575 5900);
DISPLAY INVISIBLE (-8575 5900);
FORCEPROP 1 LASTPIN (-8600 5625) $PN 1
R 1
J 0
(-8612 5637);
DISPLAY 0.787234 (-8612 5637);
PAINT MONO (-8612 5637);
DISPLAY INVISIBLE (-8612 5637);
FORCEPROP 1 LASTPIN (-8600 5825) $PN 2
R 1
J 0
(-8612 5787);
DISPLAY 0.787234 (-8612 5787);
PAINT MONO (-8612 5787);
DISPLAY INVISIBLE (-8612 5787);
FORCEPROP 1 LAST WATTAGE 1/16W
J 0
(-8575 5725);
DISPLAY 0.489362 (-8575 5725);
PAINT SKYBLUE (-8575 5725);
FORCEPROP 1 LAST MATERIAL CHIP
J 0
(-8575 5675);
DISPLAY 0.489362 (-8575 5675);
PAINT SKYBLUE (-8575 5675);
FORCEPROP 1 LAST TOLERANCE 5%
J 0
(-8575 5775);
DISPLAY 0.489362 (-8575 5775);
PAINT SKYBLUE (-8575 5775);
FORCEPROP 1 LAST VALUE 0
J 2
(-8550 5825);
DISPLAY 0.489362 (-8550 5825);
PAINT SKYBLUE (-8550 5825);
FORCEPROP 1 LAST PACK_TYPE 0402LF
J 0
(-8575 5575);
DISPLAY 0.489362 (-8575 5575);
PAINT SKYBLUE (-8575 5575);
FORCEPROP 1 LAST PART_NUMBER CS00002JB38
J 0
(-8575 5625);
DISPLAY 0.489362 (-8575 5625);
PAINT SKYBLUE (-8575 5625);
FORCEPROP 2 LAST CDS_LIB pure_quanta
R 1
J 0
(-8600 5725);
DISPLAY INVISIBLE (-8600 5725);
FORCEPROP 1 LAST PATH I132
R 1
J 0
(-8750 5675);
DISPLAY 0.978723 (-8750 5675);
PAINT WHITE (-8750 5675);
DISPLAY INVISIBLE (-8750 5675);
FORCEADD Q_RES..1
R 1
(-8250 5725);
FORCEPROP 1 LAST LOCATION PR446
J 0
(-8200 5875);
DISPLAY 0.489362 (-8200 5875);
PAINT SKYBLUE (-8200 5875);
FORCEPROP 0 LAST $SEC 1
R 1
J 0
(-8200 5900);
DISPLAY 0.680851 (-8200 5900);
PAINT MONO (-8200 5900);
DISPLAY INVISIBLE (-8200 5900);
FORCEPROP 0 LAST CDS_SEC 1
R 1
J 0
(-8200 5900);
DISPLAY 1.021277 (-8200 5900);
DISPLAY INVISIBLE (-8200 5900);
FORCEPROP 1 LASTPIN (-8250 5625) $PN 1
R 1
J 0
(-8262 5637);
DISPLAY 0.787234 (-8262 5637);
PAINT MONO (-8262 5637);
DISPLAY INVISIBLE (-8262 5637);
FORCEPROP 1 LASTPIN (-8250 5825) $PN 2
R 1
J 0
(-8262 5787);
DISPLAY 0.787234 (-8262 5787);
PAINT MONO (-8262 5787);
DISPLAY INVISIBLE (-8262 5787);
FORCEPROP 1 LAST WATTAGE 1/16W
J 0
(-8200 5725);
DISPLAY 0.489362 (-8200 5725);
PAINT SKYBLUE (-8200 5725);
FORCEPROP 1 LAST MATERIAL EMPTY
J 0
(-8200 5675);
DISPLAY 0.489362 (-8200 5675);
PAINT RED (-8200 5675);
FORCEPROP 1 LAST TOLERANCE 5%
J 0
(-8200 5775);
DISPLAY 0.489362 (-8200 5775);
PAINT SKYBLUE (-8200 5775);
FORCEPROP 1 LAST VALUE 0
J 2
(-8175 5825);
DISPLAY 0.489362 (-8175 5825);
PAINT SKYBLUE (-8175 5825);
FORCEPROP 1 LAST PART_NUMBER CS00002JB38
J 0
(-8200 5625);
DISPLAY 0.489362 (-8200 5625);
PAINT SKYBLUE (-8200 5625);
FORCEPROP 1 LAST PACK_TYPE 0402LF
J 0
(-8200 5575);
DISPLAY 0.489362 (-8200 5575);
PAINT SKYBLUE (-8200 5575);
FORCEPROP 2 LAST CDS_LIB pure_quanta
R 1
J 0
(-8250 5725);
DISPLAY INVISIBLE (-8250 5725);
FORCEPROP 1 LAST PATH I133
R 1
J 0
(-8400 5675);
DISPLAY 0.978723 (-8400 5675);
PAINT WHITE (-8400 5675);
DISPLAY INVISIBLE (-8400 5675);
FORCEADD VCC_CORE..1
(-8250 5925);
FORCEPROP 3 LASTPIN (-8250 5875) SIG_NAME P3V3_STBY\g
J 0
(-8240 5885);
DISPLAY 0.659574 (-8240 5885);
PAINT MONO (-8240 5885);
DISPLAY INVISIBLE (-8240 5885);
FORCEPROP 1 LAST HDL_POWER P3V3_STBY
J 1
(-8250 5975);
DISPLAY 0.489362 (-8250 5975);
PAINT GREEN (-8250 5975);
FORCEPROP 2 LAST CDS_LIB pure_quanta_power
J 0
(-8250 5925);
DISPLAY INVISIBLE (-8250 5925);
FORCEPROP 1 LAST PATH I134
J 0
(-8200 5950);
DISPLAY 0.872340 (-8200 5950);
PAINT AQUA (-8200 5950);
DISPLAY INVISIBLE (-8200 5950);
FORCEADD VCC_CORE..1
(-7775 5925);
FORCEPROP 3 LASTPIN (-7775 5875) SIG_NAME PVDDCR_CPU0_P0_PVCC\g
J 0
(-7765 5885);
DISPLAY 0.659574 (-7765 5885);
PAINT MONO (-7765 5885);
DISPLAY INVISIBLE (-7765 5885);
FORCEPROP 1 LAST HDL_POWER PVDDCR_CPU0_P0_PVCC
J 1
(-7775 5975);
DISPLAY 0.489362 (-7775 5975);
PAINT GREEN (-7775 5975);
FORCEPROP 2 LAST CDS_LIB pure_quanta_power
J 0
(-7775 5925);
DISPLAY INVISIBLE (-7775 5925);
FORCEPROP 1 LAST PATH I135
J 0
(-7725 5950);
DISPLAY 0.872340 (-7725 5950);
PAINT AQUA (-7725 5950);
DISPLAY INVISIBLE (-7725 5950);
FORCEADD Q_RES..2
(-750 4250);
FORCEPROP 1 LAST LOCATION PR447
J 0
(-705 4375);
DISPLAY 0.489362 (-705 4375);
PAINT SKYBLUE (-705 4375);
FORCEPROP 0 LAST $SEC 1
J 0
(-700 4400);
DISPLAY 0.680851 (-700 4400);
PAINT MONO (-700 4400);
DISPLAY INVISIBLE (-700 4400);
FORCEPROP 0 LAST CDS_SEC 1
J 0
(-700 4400);
DISPLAY 1.021277 (-700 4400);
DISPLAY INVISIBLE (-700 4400);
FORCEPROP 1 LASTPIN (-750 4350) $PN 1
J 0
(-745 4312);
DISPLAY 0.787234 (-745 4312);
PAINT MONO (-745 4312);
DISPLAY INVISIBLE (-745 4312);
FORCEPROP 1 LASTPIN (-750 4150) $PN 2
J 0
(-745 4160);
DISPLAY 0.787234 (-745 4160);
PAINT MONO (-745 4160);
DISPLAY INVISIBLE (-745 4160);
FORCEPROP 1 LAST WATTAGE 1/16W
J 0
(-710 4225);
DISPLAY 0.489362 (-710 4225);
PAINT SKYBLUE (-710 4225);
FORCEPROP 1 LAST MATERIAL CHIP
J 0
(-710 4175);
DISPLAY 0.489362 (-710 4175);
PAINT SKYBLUE (-710 4175);
FORCEPROP 1 LAST TOLERANCE 1%
J 0
(-705 4275);
DISPLAY 0.489362 (-705 4275);
PAINT SKYBLUE (-705 4275);
FORCEPROP 1 LAST VALUE 1K
J 0
(-705 4325);
DISPLAY 0.489362 (-705 4325);
PAINT SKYBLUE (-705 4325);
FORCEPROP 1 LAST PART_NUMBER TMP_QCS21002FB24
J 0
(-710 4125);
DISPLAY 0.489362 (-710 4125);
PAINT SKYBLUE (-710 4125);
FORCEPROP 1 LAST PACK_TYPE 0402LF
J 0
(-710 4075);
DISPLAY 0.489362 (-710 4075);
PAINT SKYBLUE (-710 4075);
FORCEPROP 2 LAST CDS_LIB pure_quanta
J 0
(-750 4250);
DISPLAY INVISIBLE (-750 4250);
FORCEPROP 1 LAST PATH I136
J 0
(-700 4425);
DISPLAY 0.978723 (-700 4425);
PAINT WHITE (-700 4425);
DISPLAY INVISIBLE (-700 4425);
FORCEADD UNIVERSAL_GND..1
(-8000 3900);
FORCEPROP 3 LASTPIN (-8000 3950) SIG_NAME GND\g
J 0
(-7990 3960);
DISPLAY 0.659574 (-7990 3960);
PAINT MONO (-7990 3960);
DISPLAY INVISIBLE (-7990 3960);
FORCEPROP 2 LAST CDS_LIB pure_quanta_power
J 0
(-8000 3900);
DISPLAY INVISIBLE (-8000 3900);
FORCEPROP 1 LAST PATH I14
J 0
(-7925 3900);
DISPLAY 0.872340 (-7925 3900);
PAINT AQUA (-7925 3900);
DISPLAY INVISIBLE (-7925 3900);
FORCEPROP 1 LAST HDL_POWER GND
J 1
(-7975 3825);
DISPLAY 0.872340 (-7975 3825);
PAINT GREEN (-7975 3825);
DISPLAY INVISIBLE (-7975 3825);
FORCEADD UNIVERSAL_GND..1
(-5600 3725);
FORCEPROP 3 LASTPIN (-5600 3775) SIG_NAME GND\g
J 0
(-5590 3785);
DISPLAY 0.659574 (-5590 3785);
PAINT MONO (-5590 3785);
DISPLAY INVISIBLE (-5590 3785);
FORCEPROP 2 LAST CDS_LIB pure_quanta_power
J 0
(-5600 3725);
DISPLAY INVISIBLE (-5600 3725);
FORCEPROP 1 LAST PATH I15
J 0
(-5525 3725);
DISPLAY 0.872340 (-5525 3725);
PAINT AQUA (-5525 3725);
DISPLAY INVISIBLE (-5525 3725);
FORCEPROP 1 LAST HDL_POWER GND
J 1
(-5575 3650);
DISPLAY 0.872340 (-5575 3650);
PAINT GREEN (-5575 3650);
DISPLAY INVISIBLE (-5575 3650);
FORCEADD Q_RES..1
(-4825 4800);
FORCEPROP 1 LAST LOCATION PR322
J 0
(-4875 4850);
DISPLAY 0.489362 (-4875 4850);
PAINT SKYBLUE (-4875 4850);
FORCEPROP 0 LAST $SEC 1
J 0
(-4800 4875);
DISPLAY 0.680851 (-4800 4875);
PAINT MONO (-4800 4875);
DISPLAY INVISIBLE (-4800 4875);
FORCEPROP 0 LAST CDS_SEC 1
J 0
(-4800 4875);
DISPLAY 1.021277 (-4800 4875);
DISPLAY INVISIBLE (-4800 4875);
FORCEPROP 1 LASTPIN (-4925 4800) $PN 1
J 0
(-4913 4812);
DISPLAY 0.489362 (-4913 4812);
PAINT MONO (-4913 4812);
FORCEPROP 1 LASTPIN (-4725 4800) $PN 2
J 0
(-4763 4812);
DISPLAY 0.489362 (-4763 4812);
PAINT MONO (-4763 4812);
FORCEPROP 1 LAST PACK_TYPE 0402LF
J 0
(-4725 4700);
DISPLAY 0.489362 (-4725 4700);
PAINT SKYBLUE (-4725 4700);
FORCEPROP 1 LAST MATERIAL CHIP
J 0
(-5075 4700);
DISPLAY 0.489362 (-5075 4700);
PAINT SKYBLUE (-5075 4700);
FORCEPROP 1 LAST WATTAGE 1/16W
J 0
(-4725 4750);
DISPLAY 0.489362 (-4725 4750);
PAINT SKYBLUE (-4725 4750);
FORCEPROP 1 LAST TOLERANCE 1%
J 0
(-4725 4825);
DISPLAY 0.489362 (-4725 4825);
PAINT SKYBLUE (-4725 4825);
FORCEPROP 1 LAST VALUE 4.7
J 2
(-4925 4825);
DISPLAY 0.489362 (-4925 4825);
PAINT SKYBLUE (-4925 4825);
FORCEPROP 1 LAST PART_NUMBER CS-4702FB19
J 0
(-5075 4750);
DISPLAY 0.489362 (-5075 4750);
PAINT SKYBLUE (-5075 4750);
FORCEPROP 1 LAST PATH I16
J 0
(-4875 4950);
DISPLAY 0.978723 (-4875 4950);
PAINT WHITE (-4875 4950);
DISPLAY INVISIBLE (-4875 4950);
FORCEPROP 2 LAST CDS_LIB pure_quanta
J 0
(-4825 4800);
DISPLAY INVISIBLE (-4825 4800);
FORCEADD Q_CAP..1
(-3975 4675);
FORCEPROP 1 LAST LOCATION PC489
J 0
(-3925 4800);
DISPLAY 0.489362 (-3925 4800);
PAINT SKYBLUE (-3925 4800);
FORCEPROP 0 LAST $SEC 1
J 0
(-3925 4825);
DISPLAY 0.680851 (-3925 4825);
PAINT MONO (-3925 4825);
DISPLAY INVISIBLE (-3925 4825);
FORCEPROP 0 LAST CDS_SEC 1
J 0
(-3925 4825);
DISPLAY 1.021277 (-3925 4825);
DISPLAY INVISIBLE (-3925 4825);
FORCEPROP 1 LASTPIN (-3975 4775) $PN 1
J 0
(-3965 4755);
DISPLAY 0.489362 (-3965 4755);
PAINT MONO (-3965 4755);
FORCEPROP 1 LASTPIN (-3975 4575) $PN 2
J 0
(-3965 4555);
DISPLAY 0.489362 (-3965 4555);
PAINT MONO (-3965 4555);
FORCEPROP 1 LAST PART_NUMBER CH4223K1B00
J 0
(-3925 4550);
DISPLAY 0.489362 (-3925 4550);
PAINT SKYBLUE (-3925 4550);
FORCEPROP 1 LAST PACK_TYPE 0402
J 0
(-3925 4500);
DISPLAY 0.489362 (-3925 4500);
PAINT SKYBLUE (-3925 4500);
FORCEPROP 1 LAST MATERIAL X7R
J 0
(-3925 4600);
DISPLAY 0.489362 (-3925 4600);
PAINT SKYBLUE (-3925 4600);
FORCEPROP 1 LAST TOLERANCE 10%
J 0
(-3925 4650);
DISPLAY 0.489362 (-3925 4650);
PAINT SKYBLUE (-3925 4650);
FORCEPROP 1 LAST VALUE 0.22UF
J 0
(-3925 4750);
DISPLAY 0.489362 (-3925 4750);
PAINT SKYBLUE (-3925 4750);
FORCEPROP 1 LAST VOLTAGE 16V
J 0
(-3925 4700);
DISPLAY 0.489362 (-3925 4700);
PAINT SKYBLUE (-3925 4700);
FORCEPROP 2 LAST CDS_LIB pure_quanta
J 0
(-3975 4675);
DISPLAY INVISIBLE (-3975 4675);
FORCEPROP 1 LAST PATH I17
J 0
(-3925 4825);
DISPLAY 0.978723 (-3925 4825);
PAINT WHITE (-3925 4825);
DISPLAY INVISIBLE (-3925 4825);
FORCEADD Q_CAP..1
(-4250 5325);
FORCEPROP 1 LAST LOCATION PC487_1
J 0
(-4200 5425);
DISPLAY 0.489362 (-4200 5425);
PAINT SKYBLUE (-4200 5425);
FORCEPROP 0 LAST $SEC 1
J 0
(-4200 5450);
DISPLAY 0.680851 (-4200 5450);
PAINT MONO (-4200 5450);
DISPLAY INVISIBLE (-4200 5450);
FORCEPROP 0 LAST CDS_SEC 1
J 0
(-4200 5450);
DISPLAY 1.021277 (-4200 5450);
DISPLAY INVISIBLE (-4200 5450);
FORCEPROP 1 LASTPIN (-4250 5425) $PN 1
J 0
(-4240 5405);
DISPLAY 0.489362 (-4240 5405);
PAINT MONO (-4240 5405);
FORCEPROP 1 LASTPIN (-4250 5225) $PN 2
J 0
(-4240 5205);
DISPLAY 0.489362 (-4240 5205);
PAINT MONO (-4240 5205);
FORCEPROP 1 LAST MATERIAL X6S
J 0
(-4200 5225);
DISPLAY 0.489362 (-4200 5225);
PAINT SKYBLUE (-4200 5225);
FORCEPROP 1 LAST TOLERANCE 10%
J 0
(-4200 5275);
DISPLAY 0.489362 (-4200 5275);
PAINT SKYBLUE (-4200 5275);
FORCEPROP 1 LAST VALUE 10UF
J 0
(-4200 5375);
DISPLAY 0.489362 (-4200 5375);
PAINT SKYBLUE (-4200 5375);
FORCEPROP 1 LAST VOLTAGE 25V
J 0
(-4200 5325);
DISPLAY 0.489362 (-4200 5325);
PAINT SKYBLUE (-4200 5325);
FORCEPROP 1 LAST PART_NUMBER CH6104KEA00
J 0
(-4200 5175);
DISPLAY 0.489362 (-4200 5175);
PAINT SKYBLUE (-4200 5175);
FORCEPROP 1 LAST PACK_TYPE C0805
J 0
(-4200 5125);
DISPLAY 0.489362 (-4200 5125);
PAINT SKYBLUE (-4200 5125);
FORCEPROP 2 LAST CDS_LIB pure_quanta
J 0
(-4250 5325);
DISPLAY INVISIBLE (-4250 5325);
FORCEPROP 1 LAST PATH I18
J 0
(-4200 5475);
DISPLAY 0.978723 (-4200 5475);
PAINT WHITE (-4200 5475);
DISPLAY INVISIBLE (-4200 5475);
FORCEADD Q_CAP..1
(-4550 5325);
FORCEPROP 1 LAST LOCATION PC485_1
J 0
(-4500 5425);
DISPLAY 0.489362 (-4500 5425);
PAINT SKYBLUE (-4500 5425);
FORCEPROP 0 LAST $SEC 1
J 0
(-4500 5450);
DISPLAY 0.680851 (-4500 5450);
PAINT MONO (-4500 5450);
DISPLAY INVISIBLE (-4500 5450);
FORCEPROP 0 LAST CDS_SEC 1
J 0
(-4500 5450);
DISPLAY 1.021277 (-4500 5450);
DISPLAY INVISIBLE (-4500 5450);
FORCEPROP 1 LASTPIN (-4550 5425) $PN 1
J 0
(-4540 5405);
DISPLAY 0.489362 (-4540 5405);
PAINT MONO (-4540 5405);
FORCEPROP 1 LASTPIN (-4550 5225) $PN 2
J 0
(-4540 5205);
DISPLAY 0.489362 (-4540 5205);
PAINT MONO (-4540 5205);
FORCEPROP 1 LAST PACK_TYPE C0805
J 0
(-4500 5125);
DISPLAY 0.489362 (-4500 5125);
PAINT SKYBLUE (-4500 5125);
FORCEPROP 1 LAST MATERIAL X6S
J 0
(-4500 5225);
DISPLAY 0.489362 (-4500 5225);
PAINT SKYBLUE (-4500 5225);
FORCEPROP 1 LAST TOLERANCE 10%
J 0
(-4500 5275);
DISPLAY 0.489362 (-4500 5275);
PAINT SKYBLUE (-4500 5275);
FORCEPROP 1 LAST VALUE 10UF
J 0
(-4500 5375);
DISPLAY 0.489362 (-4500 5375);
PAINT SKYBLUE (-4500 5375);
FORCEPROP 1 LAST PART_NUMBER CH6104KEA00
J 0
(-4500 5175);
DISPLAY 0.489362 (-4500 5175);
PAINT SKYBLUE (-4500 5175);
FORCEPROP 1 LAST VOLTAGE 25V
J 0
(-4500 5325);
DISPLAY 0.489362 (-4500 5325);
PAINT SKYBLUE (-4500 5325);
FORCEPROP 2 LAST CDS_LIB pure_quanta
J 0
(-4550 5325);
DISPLAY INVISIBLE (-4550 5325);
FORCEPROP 1 LAST PATH I19
J 0
(-4500 5475);
DISPLAY 0.978723 (-4500 5475);
PAINT WHITE (-4500 5475);
DISPLAY INVISIBLE (-4500 5475);
FORCEADD Q_CAP..1
(-7600 5300);
FORCEPROP 1 LAST LOCATION PC477_C0P0_1
J 0
(-7550 5400);
DISPLAY 0.489362 (-7550 5400);
PAINT SKYBLUE (-7550 5400);
FORCEPROP 0 LAST $SEC 1
J 0
(-7550 5425);
DISPLAY 0.680851 (-7550 5425);
PAINT MONO (-7550 5425);
DISPLAY INVISIBLE (-7550 5425);
FORCEPROP 0 LAST CDS_SEC 1
J 0
(-7550 5425);
DISPLAY 1.021277 (-7550 5425);
DISPLAY INVISIBLE (-7550 5425);
FORCEPROP 1 LASTPIN (-7600 5400) $PN 1
J 0
(-7590 5380);
DISPLAY 0.489362 (-7590 5380);
PAINT MONO (-7590 5380);
FORCEPROP 1 LASTPIN (-7600 5200) $PN 2
J 0
(-7590 5180);
DISPLAY 0.489362 (-7590 5180);
PAINT MONO (-7590 5180);
FORCEPROP 1 LAST PACK_TYPE C0402
J 0
(-7550 5100);
DISPLAY 0.489362 (-7550 5100);
PAINT SKYBLUE (-7550 5100);
FORCEPROP 1 LAST MATERIAL X6S
J 0
(-7550 5200);
DISPLAY 0.489362 (-7550 5200);
PAINT SKYBLUE (-7550 5200);
FORCEPROP 1 LAST TOLERANCE 10%
J 0
(-7550 5250);
DISPLAY 0.489362 (-7550 5250);
PAINT SKYBLUE (-7550 5250);
FORCEPROP 1 LAST VALUE 2.2UF
J 0
(-7550 5350);
DISPLAY 0.489362 (-7550 5350);
PAINT SKYBLUE (-7550 5350);
FORCEPROP 1 LAST PART_NUMBER CH5222KEB01
J 0
(-7550 5150);
DISPLAY 0.489362 (-7550 5150);
PAINT SKYBLUE (-7550 5150);
FORCEPROP 1 LAST VOLTAGE 10V
J 0
(-7550 5300);
DISPLAY 0.489362 (-7550 5300);
PAINT SKYBLUE (-7550 5300);
FORCEPROP 2 LAST CDS_LIB pure_quanta
J 0
(-7600 5300);
DISPLAY INVISIBLE (-7600 5300);
FORCEPROP 1 LAST PATH I2
J 0
(-7550 5450);
DISPLAY 0.978723 (-7550 5450);
PAINT WHITE (-7550 5450);
DISPLAY INVISIBLE (-7550 5450);
FORCEADD Q_CAP..1
(-4875 5325);
FORCEPROP 1 LAST LOCATION PC483_1
J 0
(-4825 5425);
DISPLAY 0.489362 (-4825 5425);
PAINT SKYBLUE (-4825 5425);
FORCEPROP 0 LAST $SEC 1
J 0
(-4825 5450);
DISPLAY 0.680851 (-4825 5450);
PAINT MONO (-4825 5450);
DISPLAY INVISIBLE (-4825 5450);
FORCEPROP 0 LAST CDS_SEC 1
J 0
(-4825 5450);
DISPLAY 1.021277 (-4825 5450);
DISPLAY INVISIBLE (-4825 5450);
FORCEPROP 1 LASTPIN (-4875 5425) $PN 1
J 0
(-4865 5405);
DISPLAY 0.489362 (-4865 5405);
PAINT MONO (-4865 5405);
FORCEPROP 1 LASTPIN (-4875 5225) $PN 2
J 0
(-4865 5205);
DISPLAY 0.489362 (-4865 5205);
PAINT MONO (-4865 5205);
FORCEPROP 1 LAST MATERIAL X6S
J 0
(-4825 5225);
DISPLAY 0.489362 (-4825 5225);
PAINT SKYBLUE (-4825 5225);
FORCEPROP 1 LAST TOLERANCE 10%
J 0
(-4825 5275);
DISPLAY 0.489362 (-4825 5275);
PAINT SKYBLUE (-4825 5275);
FORCEPROP 1 LAST VALUE 10UF
J 0
(-4825 5375);
DISPLAY 0.489362 (-4825 5375);
PAINT SKYBLUE (-4825 5375);
FORCEPROP 1 LAST PART_NUMBER CH6104KEA00
J 0
(-4825 5175);
DISPLAY 0.489362 (-4825 5175);
PAINT SKYBLUE (-4825 5175);
FORCEPROP 1 LAST VOLTAGE 25V
J 0
(-4825 5325);
DISPLAY 0.489362 (-4825 5325);
PAINT SKYBLUE (-4825 5325);
FORCEPROP 1 LAST PACK_TYPE C0805
J 0
(-4825 5125);
DISPLAY 0.489362 (-4825 5125);
PAINT SKYBLUE (-4825 5125);
FORCEPROP 2 LAST CDS_LIB pure_quanta
J 0
(-4875 5325);
DISPLAY INVISIBLE (-4875 5325);
FORCEPROP 1 LAST PATH I20
J 0
(-4825 5475);
DISPLAY 0.978723 (-4825 5475);
PAINT WHITE (-4825 5475);
DISPLAY INVISIBLE (-4825 5475);
FORCEADD Q_CAP..1
(-5200 5325);
FORCEPROP 1 LAST LOCATION PC481_1
J 0
(-5150 5425);
DISPLAY 0.489362 (-5150 5425);
PAINT SKYBLUE (-5150 5425);
FORCEPROP 0 LAST $SEC 1
J 0
(-5150 5450);
DISPLAY 0.680851 (-5150 5450);
PAINT MONO (-5150 5450);
DISPLAY INVISIBLE (-5150 5450);
FORCEPROP 0 LAST CDS_SEC 1
J 0
(-5150 5450);
DISPLAY 1.021277 (-5150 5450);
DISPLAY INVISIBLE (-5150 5450);
FORCEPROP 1 LASTPIN (-5200 5425) $PN 1
J 0
(-5190 5405);
DISPLAY 0.489362 (-5190 5405);
PAINT MONO (-5190 5405);
FORCEPROP 1 LASTPIN (-5200 5225) $PN 2
J 0
(-5190 5205);
DISPLAY 0.489362 (-5190 5205);
PAINT MONO (-5190 5205);
FORCEPROP 1 LAST PACK_TYPE C0402
J 0
(-5150 5125);
DISPLAY 0.489362 (-5150 5125);
PAINT SKYBLUE (-5150 5125);
FORCEPROP 1 LAST MATERIAL X6S
J 0
(-5150 5225);
DISPLAY 0.489362 (-5150 5225);
PAINT SKYBLUE (-5150 5225);
FORCEPROP 1 LAST TOLERANCE 10%
J 0
(-5150 5275);
DISPLAY 0.489362 (-5150 5275);
PAINT SKYBLUE (-5150 5275);
FORCEPROP 1 LAST VALUE 1UF
J 0
(-5150 5375);
DISPLAY 0.489362 (-5150 5375);
PAINT SKYBLUE (-5150 5375);
FORCEPROP 1 LAST PART_NUMBER CH5104KEB02
J 0
(-5150 5175);
DISPLAY 0.489362 (-5150 5175);
PAINT SKYBLUE (-5150 5175);
FORCEPROP 1 LAST VOLTAGE 25V
J 0
(-5150 5325);
DISPLAY 0.489362 (-5150 5325);
PAINT SKYBLUE (-5150 5325);
FORCEPROP 2 LAST CDS_LIB pure_quanta
J 0
(-5200 5325);
DISPLAY INVISIBLE (-5200 5325);
FORCEPROP 1 LAST PATH I21
J 0
(-5150 5475);
DISPLAY 0.978723 (-5150 5475);
PAINT WHITE (-5150 5475);
DISPLAY INVISIBLE (-5150 5475);
FORCEADD Q_INDUCTOR..1
(-3050 5525);
FORCEPROP 1 LAST LOCATION PL53
J 0
(-3175 5685);
DISPLAY 0.489362 (-3175 5685);
PAINT SKYBLUE (-3175 5685);
FORCEPROP 0 LAST $SEC 1
J 0
(-3175 5800);
DISPLAY 0.680851 (-3175 5800);
PAINT MONO (-3175 5800);
DISPLAY INVISIBLE (-3175 5800);
FORCEPROP 0 LAST CDS_SEC 1
J 0
(-3175 5800);
DISPLAY 1.021277 (-3175 5800);
DISPLAY INVISIBLE (-3175 5800);
FORCEPROP 0 LASTPIN (-3150 5500) $PN 1
J 2
(-3160 5510);
DISPLAY 0.489362 (-3160 5510);
PAINT MONO (-3160 5510);
FORCEPROP 0 LASTPIN (-2950 5500) $PN 2
J 0
(-2940 5510);
DISPLAY 0.489362 (-2940 5510);
PAINT MONO (-2940 5510);
FORCEPROP 1 LAST MATERIAL IND
J 0
(-3175 5580);
DISPLAY 0.489362 (-3175 5580);
PAINT SKYBLUE (-3175 5580);
FORCEPROP 1 LAST PART_NUMBER CVA50^0MZ09
J 0
(-3175 5635);
DISPLAY 0.489362 (-3175 5635);
PAINT SKYBLUE (-3175 5635);
FORCEPROP 2 LAST VALUE 50NH/86A
J 0
(-3175 5775);
DISPLAY 0.489362 (-3175 5775);
PAINT SKYBLUE (-3175 5775);
FORCEPROP 2 LAST PACK_TYPE SMLF
J 0
(-3175 5725);
DISPLAY 0.489362 (-3175 5725);
PAINT SKYBLUE (-3175 5725);
FORCEPROP 1 LAST NEEDS_NO_SIZE TRUE
J 0
(-3050 5525);
DISPLAY 0.468085 (-3050 5525);
PAINT GREEN (-3050 5525);
DISPLAY INVISIBLE (-3050 5525);
FORCEPROP 2 LAST CDS_LIB pure_quanta
J 0
(-3050 5525);
DISPLAY INVISIBLE (-3050 5525);
FORCEPROP 1 LAST PATH I24
J 0
(-2975 5580);
DISPLAY 0.723404 (-2975 5580);
PAINT GREEN (-2975 5580);
DISPLAY INVISIBLE (-2975 5580);
FORCEADD VCC_CORE..1
(-4000 5600);
FORCEPROP 3 LASTPIN (-4000 5550) SIG_NAME SW_P12V_STBY_PVDDCR_CPU0_P0_FLT\g
J 0
(-3990 5560);
DISPLAY 0.659574 (-3990 5560);
PAINT MONO (-3990 5560);
DISPLAY INVISIBLE (-3990 5560);
FORCEPROP 1 LAST HDL_POWER SW_P12V_STBY_PVDDCR_CPU0_P0_FLT
J 1
(-4000 5650);
DISPLAY 0.489362 (-4000 5650);
PAINT GREEN (-4000 5650);
FORCEPROP 2 LAST CDS_LIB pure_quanta_power
J 0
(-4000 5600);
DISPLAY INVISIBLE (-4000 5600);
FORCEPROP 1 LAST PATH I25
J 0
(-3950 5625);
DISPLAY 0.872340 (-3950 5625);
PAINT AQUA (-3950 5625);
DISPLAY INVISIBLE (-3950 5625);
FORCEADD Q_CAPP..1
(-3925 5325);
FORCEPROP 1 LAST LOCATION PC491
J 0
(-3875 5425);
DISPLAY 0.489362 (-3875 5425);
PAINT SKYBLUE (-3875 5425);
FORCEPROP 0 LAST $SEC 1
J 0
(-3875 5450);
DISPLAY 0.680851 (-3875 5450);
PAINT MONO (-3875 5450);
DISPLAY INVISIBLE (-3875 5450);
FORCEPROP 0 LAST CDS_SEC 1
J 0
(-3875 5450);
DISPLAY 1.021277 (-3875 5450);
DISPLAY INVISIBLE (-3875 5450);
FORCEPROP 1 LASTPIN (-3925 5425) $PN 1
J 0
(-3915 5410);
DISPLAY 0.489362 (-3915 5410);
PAINT MONO (-3915 5410);
FORCEPROP 1 LASTPIN (-3925 5225) $PN 2
J 0
(-3915 5210);
DISPLAY 0.489362 (-3915 5210);
PAINT MONO (-3915 5210);
FORCEPROP 1 LAST TOLERANCE 20%
J 0
(-3875 5325);
DISPLAY 0.489362 (-3875 5325);
PAINT SKYBLUE (-3875 5325);
FORCEPROP 1 LAST VALUE 220UF
J 0
(-3875 5375);
DISPLAY 0.489362 (-3875 5375);
PAINT SKYBLUE (-3875 5375);
FORCEPROP 1 LAST PACK_TYPE THLF
J 0
(-3875 5175);
DISPLAY 0.489362 (-3875 5175);
PAINT SKYBLUE (-3875 5175);
FORCEPROP 1 LAST MATERIAL OSCON
J 0
(-3875 5225);
DISPLAY 0.489362 (-3875 5225);
PAINT SKYBLUE (-3875 5225);
FORCEPROP 1 LAST PART_NUMBER CC72204MD02
J 0
(-3875 5125);
DISPLAY 0.489362 (-3875 5125);
PAINT SKYBLUE (-3875 5125);
FORCEPROP 1 LAST VOLTAGE 25V
J 0
(-3875 5275);
DISPLAY 0.489362 (-3875 5275);
PAINT SKYBLUE (-3875 5275);
FORCEPROP 2 LAST CDS_LIB pure_quanta
J 0
(-3925 5325);
DISPLAY INVISIBLE (-3925 5325);
FORCEPROP 1 LAST PATH I26
J 0
(-3875 5475);
DISPLAY 0.978723 (-3875 5475);
DISPLAY INVISIBLE (-3875 5475);
FORCEADD Q_CAPP..1
(-3500 5325);
FORCEPROP 1 LAST LOCATION PC492
J 0
(-3450 5425);
DISPLAY 0.489362 (-3450 5425);
PAINT SKYBLUE (-3450 5425);
FORCEPROP 0 LAST $SEC 1
J 0
(-3450 5450);
DISPLAY 0.680851 (-3450 5450);
PAINT MONO (-3450 5450);
DISPLAY INVISIBLE (-3450 5450);
FORCEPROP 0 LAST CDS_SEC 1
J 0
(-3450 5450);
DISPLAY 1.021277 (-3450 5450);
DISPLAY INVISIBLE (-3450 5450);
FORCEPROP 1 LASTPIN (-3500 5425) $PN 1
J 0
(-3490 5410);
DISPLAY 0.489362 (-3490 5410);
PAINT MONO (-3490 5410);
FORCEPROP 1 LASTPIN (-3500 5225) $PN 2
J 0
(-3490 5210);
DISPLAY 0.489362 (-3490 5210);
PAINT MONO (-3490 5210);
FORCEPROP 1 LAST PART_NUMBER CC72204MD02
J 0
(-3450 5125);
DISPLAY 0.489362 (-3450 5125);
PAINT SKYBLUE (-3450 5125);
FORCEPROP 1 LAST PACK_TYPE THLF
J 0
(-3450 5175);
DISPLAY 0.489362 (-3450 5175);
PAINT SKYBLUE (-3450 5175);
FORCEPROP 1 LAST MATERIAL OSCON
J 0
(-3450 5225);
DISPLAY 0.489362 (-3450 5225);
PAINT SKYBLUE (-3450 5225);
FORCEPROP 1 LAST TOLERANCE 20%
J 0
(-3450 5325);
DISPLAY 0.489362 (-3450 5325);
PAINT SKYBLUE (-3450 5325);
FORCEPROP 1 LAST VALUE 220UF
J 0
(-3450 5375);
DISPLAY 0.489362 (-3450 5375);
PAINT SKYBLUE (-3450 5375);
FORCEPROP 1 LAST VOLTAGE 25V
J 0
(-3450 5275);
DISPLAY 0.489362 (-3450 5275);
PAINT SKYBLUE (-3450 5275);
FORCEPROP 2 LAST CDS_LIB pure_quanta
J 0
(-3500 5325);
DISPLAY INVISIBLE (-3500 5325);
FORCEPROP 1 LAST PATH I27
J 0
(-3450 5475);
DISPLAY 0.978723 (-3450 5475);
DISPLAY INVISIBLE (-3450 5475);
FORCEADD Q_RES..2
(-7950 5300);
FORCEPROP 1 LAST LOCATION PR318
J 0
(-7900 5425);
DISPLAY 0.489362 (-7900 5425);
PAINT SKYBLUE (-7900 5425);
FORCEPROP 0 LAST $SEC 1
J 0
(-7900 5450);
DISPLAY 0.680851 (-7900 5450);
PAINT MONO (-7900 5450);
DISPLAY INVISIBLE (-7900 5450);
FORCEPROP 0 LAST CDS_SEC 1
J 0
(-7900 5450);
DISPLAY 1.021277 (-7900 5450);
DISPLAY INVISIBLE (-7900 5450);
FORCEPROP 1 LASTPIN (-7950 5400) $PN 1
J 0
(-7935 5510);
DISPLAY 0.489362 (-7935 5510);
PAINT MONO (-7935 5510);
FORCEPROP 1 LASTPIN (-7950 5200) $PN 2
J 0
(-7945 5210);
DISPLAY 0.489362 (-7945 5210);
PAINT MONO (-7945 5210);
FORCEPROP 1 LAST PART_NUMBER CS-2202FB00
J 0
(-7900 5175);
DISPLAY 0.489362 (-7900 5175);
PAINT SKYBLUE (-7900 5175);
FORCEPROP 1 LAST WATTAGE 1/16W
J 0
(-7900 5275);
DISPLAY 0.489362 (-7900 5275);
PAINT SKYBLUE (-7900 5275);
FORCEPROP 1 LAST MATERIAL CHIP
J 0
(-7900 5225);
DISPLAY 0.489362 (-7900 5225);
PAINT SKYBLUE (-7900 5225);
FORCEPROP 1 LAST TOLERANCE 1%
J 0
(-7900 5325);
DISPLAY 0.489362 (-7900 5325);
PAINT SKYBLUE (-7900 5325);
FORCEPROP 1 LAST VALUE 2.2
J 0
(-7900 5375);
DISPLAY 0.489362 (-7900 5375);
PAINT SKYBLUE (-7900 5375);
FORCEPROP 1 LAST PACK_TYPE 0402LF
J 0
(-7900 5125);
DISPLAY 0.489362 (-7900 5125);
PAINT SKYBLUE (-7900 5125);
FORCEPROP 2 LAST CDS_LIB pure_quanta
J 0
(-7950 5300);
DISPLAY INVISIBLE (-7950 5300);
FORCEPROP 1 LAST PATH I3
J 0
(-7900 5475);
DISPLAY 0.978723 (-7900 5475);
PAINT WHITE (-7900 5475);
DISPLAY INVISIBLE (-7900 5475);
FORCEADD VCC_CORE..1
(-2750 5600);
FORCEPROP 3 LASTPIN (-2750 5550) SIG_NAME P12V_STBY\g
J 0
(-2740 5560);
DISPLAY 0.659574 (-2740 5560);
PAINT MONO (-2740 5560);
DISPLAY INVISIBLE (-2740 5560);
FORCEPROP 1 LAST HDL_POWER P12V_STBY
J 1
(-2750 5650);
DISPLAY 0.489362 (-2750 5650);
PAINT GREEN (-2750 5650);
FORCEPROP 2 LAST CDS_LIB pure_quanta_power
J 0
(-2750 5600);
DISPLAY INVISIBLE (-2750 5600);
FORCEPROP 1 LAST PATH I30
J 0
(-2700 5625);
DISPLAY 0.872340 (-2700 5625);
PAINT AQUA (-2700 5625);
DISPLAY INVISIBLE (-2700 5625);
FORCEADD Q_INDUCTOR4P_14..1
(-3225 4325);
FORCEPROP 1 LAST LOCATION PL51
J 0
(-3450 4580);
DISPLAY 0.489362 (-3450 4580);
PAINT SKYBLUE (-3450 4580);
FORCEPROP 0 LAST $SEC 1
J 0
(-3450 4725);
DISPLAY 0.680851 (-3450 4725);
PAINT MONO (-3450 4725);
DISPLAY INVISIBLE (-3450 4725);
FORCEPROP 0 LAST CDS_SEC 1
J 0
(-3450 4725);
DISPLAY 1.021277 (-3450 4725);
DISPLAY INVISIBLE (-3450 4725);
FORCEPROP 0 LASTPIN (-3625 4450) $PN 1
J 2
(-3635 4460);
DISPLAY 0.489362 (-3635 4460);
PAINT MONO (-3635 4460);
FORCEPROP 0 LASTPIN (-3625 4200) $PN 2
J 2
(-3635 4210);
DISPLAY 0.489362 (-3635 4210);
PAINT MONO (-3635 4210);
FORCEPROP 0 LASTPIN (-2825 4200) $PN 3
J 0
(-2815 4210);
DISPLAY 0.489362 (-2815 4210);
PAINT MONO (-2815 4210);
FORCEPROP 0 LASTPIN (-2825 4450) $PN 4
J 0
(-2815 4460);
DISPLAY 0.489362 (-2815 4460);
PAINT MONO (-2815 4460);
FORCEPROP 2 LAST PART_TYPE SMLF
J 0
(-3450 4675);
DISPLAY 1.021277 (-3450 4675);
FORCEPROP 1 LAST PART_NUMBER CV+15^0TZ04
J 0
(-3450 4485);
DISPLAY 0.489362 (-3450 4485);
PAINT SKYBLUE (-3450 4485);
FORCEPROP 1 LAST MATERIAL IND
J 0
(-3450 4535);
DISPLAY 0.489362 (-3450 4535);
PAINT SKYBLUE (-3450 4535);
FORCEPROP 2 LAST VALUE 150NH
J 0
(-3450 4625);
DISPLAY 0.489362 (-3450 4625);
PAINT SKYBLUE (-3450 4625);
FORCEPROP 1 LAST NEEDS_NO_SIZE TRUE
J 0
(-3225 4325);
DISPLAY 0.468085 (-3225 4325);
PAINT GREEN (-3225 4325);
DISPLAY INVISIBLE (-3225 4325);
FORCEPROP 2 LAST CDS_LIB pure_quanta
J 0
(-3225 4325);
DISPLAY INVISIBLE (-3225 4325);
FORCEPROP 1 LAST PATH I31
J 0
(-3025 4480);
DISPLAY 0.723404 (-3025 4480);
PAINT GREEN (-3025 4480);
DISPLAY INVISIBLE (-3025 4480);
FORCEADD Q_CAP..1
(-1150 4275);
FORCEPROP 1 LAST LOCATION PC502_1
J 0
(-1100 4375);
DISPLAY 0.489362 (-1100 4375);
PAINT SKYBLUE (-1100 4375);
FORCEPROP 0 LAST $SEC 1
J 0
(-1100 4400);
DISPLAY 0.680851 (-1100 4400);
PAINT MONO (-1100 4400);
DISPLAY INVISIBLE (-1100 4400);
FORCEPROP 0 LAST CDS_SEC 1
J 0
(-1100 4400);
DISPLAY 1.021277 (-1100 4400);
DISPLAY INVISIBLE (-1100 4400);
FORCEPROP 1 LASTPIN (-1150 4375) $PN 1
J 0
(-1140 4355);
DISPLAY 0.489362 (-1140 4355);
PAINT MONO (-1140 4355);
FORCEPROP 1 LASTPIN (-1150 4175) $PN 2
J 0
(-1140 4155);
DISPLAY 0.489362 (-1140 4155);
PAINT MONO (-1140 4155);
FORCEPROP 1 LAST MATERIAL X6S
J 0
(-1100 4175);
DISPLAY 0.489362 (-1100 4175);
PAINT SKYBLUE (-1100 4175);
FORCEPROP 1 LAST TOLERANCE 20%
J 0
(-1100 4225);
DISPLAY 0.489362 (-1100 4225);
PAINT SKYBLUE (-1100 4225);
FORCEPROP 1 LAST VALUE 22UF
J 0
(-1100 4325);
DISPLAY 0.489362 (-1100 4325);
PAINT SKYBLUE (-1100 4325);
FORCEPROP 1 LAST VOLTAGE 4V
J 0
(-1100 4275);
DISPLAY 0.489362 (-1100 4275);
PAINT SKYBLUE (-1100 4275);
FORCEPROP 1 LAST PACK_TYPE 0805
J 0
(-1100 4125);
DISPLAY 0.489362 (-1100 4125);
PAINT SKYBLUE (-1100 4125);
FORCEPROP 2 LAST CDS_LIB pure_quanta
J 0
(-1150 4275);
DISPLAY INVISIBLE (-1150 4275);
FORCEPROP 1 LAST PATH I32
J 0
(-1100 4425);
DISPLAY 0.978723 (-1100 4425);
PAINT WHITE (-1100 4425);
DISPLAY INVISIBLE (-1100 4425);
FORCEPROP 1 LAST PART_NUMBER TMP_QCH622KMEA01
J 0
(-1100 4125);
DISPLAY 0.489362 (-1100 4125);
PAINT SKYBLUE (-1100 4125);
DISPLAY INVISIBLE (-1100 4125);
FORCEADD Q_CAP..1
(-1600 4275);
FORCEPROP 1 LAST LOCATION PC500_1
J 0
(-1550 4375);
DISPLAY 0.489362 (-1550 4375);
PAINT SKYBLUE (-1550 4375);
FORCEPROP 0 LAST $SEC 1
J 0
(-1550 4400);
DISPLAY 0.680851 (-1550 4400);
PAINT MONO (-1550 4400);
DISPLAY INVISIBLE (-1550 4400);
FORCEPROP 0 LAST CDS_SEC 1
J 0
(-1550 4400);
DISPLAY 1.021277 (-1550 4400);
DISPLAY INVISIBLE (-1550 4400);
FORCEPROP 1 LASTPIN (-1600 4375) $PN 1
J 0
(-1590 4355);
DISPLAY 0.489362 (-1590 4355);
PAINT MONO (-1590 4355);
FORCEPROP 1 LASTPIN (-1600 4175) $PN 2
J 0
(-1590 4155);
DISPLAY 0.489362 (-1590 4155);
PAINT MONO (-1590 4155);
FORCEPROP 1 LAST MATERIAL X6S
J 0
(-1550 4175);
DISPLAY 0.489362 (-1550 4175);
PAINT SKYBLUE (-1550 4175);
FORCEPROP 1 LAST TOLERANCE 20%
J 0
(-1550 4225);
DISPLAY 0.489362 (-1550 4225);
PAINT SKYBLUE (-1550 4225);
FORCEPROP 1 LAST VALUE 22UF
J 0
(-1550 4325);
DISPLAY 0.489362 (-1550 4325);
PAINT SKYBLUE (-1550 4325);
FORCEPROP 1 LAST PART_NUMBER TMP_QCH622KMEA01
J 0
(-1550 4125);
DISPLAY 0.489362 (-1550 4125);
PAINT SKYBLUE (-1550 4125);
FORCEPROP 1 LAST VOLTAGE 4V
J 0
(-1550 4275);
DISPLAY 0.489362 (-1550 4275);
PAINT SKYBLUE (-1550 4275);
FORCEPROP 1 LAST PACK_TYPE 0805
J 0
(-1550 4075);
DISPLAY 0.489362 (-1550 4075);
PAINT SKYBLUE (-1550 4075);
FORCEPROP 2 LAST CDS_LIB pure_quanta
J 0
(-1600 4275);
DISPLAY INVISIBLE (-1600 4275);
FORCEPROP 1 LAST PATH I33
J 0
(-1550 4425);
DISPLAY 0.978723 (-1550 4425);
PAINT WHITE (-1550 4425);
DISPLAY INVISIBLE (-1550 4425);
FORCEADD Q_CAP..1
(-1975 4275);
FORCEPROP 1 LAST LOCATION PC497
J 0
(-1925 4375);
DISPLAY 0.489362 (-1925 4375);
PAINT SKYBLUE (-1925 4375);
FORCEPROP 0 LAST $SEC 1
J 0
(-1925 4400);
DISPLAY 0.680851 (-1925 4400);
PAINT MONO (-1925 4400);
DISPLAY INVISIBLE (-1925 4400);
FORCEPROP 0 LAST CDS_SEC 1
J 0
(-1925 4400);
DISPLAY 1.021277 (-1925 4400);
DISPLAY INVISIBLE (-1925 4400);
FORCEPROP 1 LASTPIN (-1975 4375) $PN 1
J 0
(-1965 4355);
DISPLAY 0.489362 (-1965 4355);
PAINT MONO (-1965 4355);
FORCEPROP 1 LASTPIN (-1975 4175) $PN 2
J 0
(-1965 4155);
DISPLAY 0.489362 (-1965 4155);
PAINT MONO (-1965 4155);
FORCEPROP 1 LAST MATERIAL X7R
J 0
(-1925 4175);
DISPLAY 0.489362 (-1925 4175);
PAINT SKYBLUE (-1925 4175);
FORCEPROP 1 LAST TOLERANCE 10%
J 0
(-1925 4225);
DISPLAY 0.489362 (-1925 4225);
PAINT SKYBLUE (-1925 4225);
FORCEPROP 1 LAST VALUE 0.1UF
J 0
(-1925 4325);
DISPLAY 0.489362 (-1925 4325);
PAINT SKYBLUE (-1925 4325);
FORCEPROP 1 LAST PART_NUMBER CH4104K1B00
J 0
(-1925 4125);
DISPLAY 0.489362 (-1925 4125);
PAINT SKYBLUE (-1925 4125);
FORCEPROP 1 LAST VOLTAGE 25V
J 0
(-1925 4275);
DISPLAY 0.489362 (-1925 4275);
PAINT SKYBLUE (-1925 4275);
FORCEPROP 1 LAST PACK_TYPE 0402
J 0
(-1925 4075);
DISPLAY 0.489362 (-1925 4075);
PAINT SKYBLUE (-1925 4075);
FORCEPROP 2 LAST CDS_LIB pure_quanta
J 0
(-1975 4275);
DISPLAY INVISIBLE (-1975 4275);
FORCEPROP 1 LAST PATH I35
J 0
(-1925 4425);
DISPLAY 0.978723 (-1925 4425);
PAINT WHITE (-1925 4425);
DISPLAY INVISIBLE (-1925 4425);
FORCEADD UNIVERSAL_GND..1
(-750 3900);
FORCEPROP 3 LASTPIN (-750 3950) SIG_NAME GND\g
J 0
(-740 3960);
DISPLAY 0.659574 (-740 3960);
PAINT MONO (-740 3960);
DISPLAY INVISIBLE (-740 3960);
FORCEPROP 2 LAST CDS_LIB pure_quanta_power
J 0
(-750 3900);
DISPLAY INVISIBLE (-750 3900);
FORCEPROP 1 LAST PATH I36
J 0
(-675 3900);
DISPLAY 0.872340 (-675 3900);
PAINT AQUA (-675 3900);
DISPLAY INVISIBLE (-675 3900);
FORCEPROP 1 LAST HDL_POWER GND
J 1
(-725 3825);
DISPLAY 0.872340 (-725 3825);
PAINT GREEN (-725 3825);
DISPLAY INVISIBLE (-725 3825);
FORCEADD VCC_CORE..1
(-750 4625);
FORCEPROP 3 LASTPIN (-750 4575) SIG_NAME PVDDCR_CPU0_P0\g
J 0
(-740 4585);
DISPLAY 0.659574 (-740 4585);
PAINT MONO (-740 4585);
DISPLAY INVISIBLE (-740 4585);
FORCEPROP 1 LAST HDL_POWER PVDDCR_CPU0_P0
J 1
(-750 4675);
DISPLAY 0.489362 (-750 4675);
PAINT GREEN (-750 4675);
FORCEPROP 2 LAST CDS_LIB pure_quanta_power
J 0
(-750 4625);
DISPLAY INVISIBLE (-750 4625);
FORCEPROP 1 LAST PATH I37
J 0
(-700 4650);
DISPLAY 0.872340 (-700 4650);
PAINT AQUA (-700 4650);
DISPLAY INVISIBLE (-700 4650);
FORCEADD OFFPAGE..3
(-2300 4200);
FORCEPROP 2 LAST $XR0 170 
J 0
(-2086 4200);
DISPLAY 0.638298 (-2086 4200);
PAINT MONO (-2086 4200);
FORCEPROP 1 LAST OFFPAGE TRUE
J 0
(-1975 4075);
DISPLAY 0.872340 (-1975 4075);
PAINT GREEN (-1975 4075);
DISPLAY INVISIBLE (-1975 4075);
FORCEPROP 1 LAST COMMENT_BODY TRUE
J 0
(-2350 4100);
DISPLAY 0.872340 (-2350 4100);
PAINT GREEN (-2350 4100);
DISPLAY INVISIBLE (-2350 4100);
FORCEPROP 2 LAST PATH I39
J 2
(-2350 4275);
DISPLAY 1.021277 (-2350 4275);
DISPLAY INVISIBLE (-2350 4275);
FORCEPROP 2 LAST CDS_LIB standard
J 2
(-2300 4200);
DISPLAY INVISIBLE (-2300 4200);
FORCEADD Q_CAP..1
(-7950 4800);
FORCEPROP 1 LAST LOCATION PC475
J 0
(-7900 4900);
DISPLAY 0.489362 (-7900 4900);
PAINT SKYBLUE (-7900 4900);
FORCEPROP 0 LAST $SEC 1
J 0
(-7900 4925);
DISPLAY 0.680851 (-7900 4925);
PAINT MONO (-7900 4925);
DISPLAY INVISIBLE (-7900 4925);
FORCEPROP 0 LAST CDS_SEC 1
J 0
(-7900 4925);
DISPLAY 1.021277 (-7900 4925);
DISPLAY INVISIBLE (-7900 4925);
FORCEPROP 1 LASTPIN (-7950 4900) $PN 1
J 0
(-7940 4880);
DISPLAY 0.489362 (-7940 4880);
PAINT MONO (-7940 4880);
FORCEPROP 1 LASTPIN (-7950 4700) $PN 2
J 0
(-7940 4680);
DISPLAY 0.489362 (-7940 4680);
PAINT MONO (-7940 4680);
FORCEPROP 1 LAST MATERIAL X6S
J 0
(-7900 4700);
DISPLAY 0.489362 (-7900 4700);
PAINT SKYBLUE (-7900 4700);
FORCEPROP 1 LAST TOLERANCE 10%
J 0
(-7900 4750);
DISPLAY 0.489362 (-7900 4750);
PAINT SKYBLUE (-7900 4750);
FORCEPROP 1 LAST VALUE 2.2UF
J 0
(-7900 4850);
DISPLAY 0.489362 (-7900 4850);
PAINT SKYBLUE (-7900 4850);
FORCEPROP 1 LAST PART_NUMBER CH5222KEB01
J 0
(-7900 4650);
DISPLAY 0.489362 (-7900 4650);
PAINT SKYBLUE (-7900 4650);
FORCEPROP 1 LAST VOLTAGE 10V
J 0
(-7900 4800);
DISPLAY 0.489362 (-7900 4800);
PAINT SKYBLUE (-7900 4800);
FORCEPROP 1 LAST PACK_TYPE C0402
J 0
(-7900 4600);
DISPLAY 0.489362 (-7900 4600);
PAINT SKYBLUE (-7900 4600);
FORCEPROP 2 LAST CDS_LIB pure_quanta
J 0
(-7950 4800);
DISPLAY INVISIBLE (-7950 4800);
FORCEPROP 1 LAST PATH I4
J 0
(-7900 4950);
DISPLAY 0.978723 (-7900 4950);
PAINT WHITE (-7900 4950);
DISPLAY INVISIBLE (-7900 4950);
FORCEADD Q_RES..1
(-4350 3500);
FORCEPROP 1 LAST LOCATION PR324
J 0
(-4400 3550);
DISPLAY 0.489362 (-4400 3550);
PAINT SKYBLUE (-4400 3550);
FORCEPROP 0 LAST $SEC 1
J 0
(-4350 3575);
DISPLAY 0.680851 (-4350 3575);
PAINT MONO (-4350 3575);
DISPLAY INVISIBLE (-4350 3575);
FORCEPROP 0 LAST CDS_SEC 1
J 0
(-4350 3575);
DISPLAY 1.021277 (-4350 3575);
DISPLAY INVISIBLE (-4350 3575);
FORCEPROP 1 LASTPIN (-4450 3500) $PN 1
J 0
(-4438 3512);
DISPLAY 0.489362 (-4438 3512);
PAINT MONO (-4438 3512);
FORCEPROP 1 LASTPIN (-4250 3500) $PN 2
J 0
(-4288 3512);
DISPLAY 0.489362 (-4288 3512);
PAINT MONO (-4288 3512);
FORCEPROP 1 LAST WATTAGE 1/16W
J 0
(-4250 3450);
DISPLAY 0.489362 (-4250 3450);
PAINT SKYBLUE (-4250 3450);
FORCEPROP 1 LAST MATERIAL CHIP
J 0
(-4600 3400);
DISPLAY 0.489362 (-4600 3400);
PAINT SKYBLUE (-4600 3400);
FORCEPROP 1 LAST TOLERANCE 5%
J 0
(-4225 3525);
DISPLAY 0.489362 (-4225 3525);
PAINT SKYBLUE (-4225 3525);
FORCEPROP 1 LAST VALUE 0
J 2
(-4475 3525);
DISPLAY 0.489362 (-4475 3525);
PAINT SKYBLUE (-4475 3525);
FORCEPROP 1 LAST PART_NUMBER CS00002JB38
J 0
(-4700 3450);
DISPLAY 0.489362 (-4700 3450);
PAINT SKYBLUE (-4700 3450);
FORCEPROP 1 LAST PACK_TYPE 0402LF
J 0
(-4250 3400);
DISPLAY 0.489362 (-4250 3400);
PAINT SKYBLUE (-4250 3400);
FORCEPROP 2 LAST CDS_LIB pure_quanta
J 0
(-4350 3500);
DISPLAY INVISIBLE (-4350 3500);
FORCEPROP 1 LAST PATH I40
J 0
(-4400 3650);
DISPLAY 0.978723 (-4400 3650);
PAINT WHITE (-4400 3650);
DISPLAY INVISIBLE (-4400 3650);
FORCEADD OFFPAGE..1
(-8225 4350);
FORCEPROP 2 LAST $XR5 175 
J 0
(-9077 4350);
DISPLAY 0.638298 (-9077 4350);
PAINT MONO (-9077 4350);
FORCEPROP 2 LAST $XR4 174 
J 0
(-8957 4350);
DISPLAY 0.638298 (-8957 4350);
PAINT MONO (-8957 4350);
FORCEPROP 2 LAST $XR3 172 
J 0
(-8837 4350);
DISPLAY 0.638298 (-8837 4350);
PAINT MONO (-8837 4350);
FORCEPROP 2 LAST $XR2 171 
J 0
(-8717 4350);
DISPLAY 0.638298 (-8717 4350);
PAINT MONO (-8717 4350);
FORCEPROP 2 LAST $XR1 170 
J 0
(-8597 4350);
DISPLAY 0.638298 (-8597 4350);
PAINT MONO (-8597 4350);
FORCEPROP 2 LAST $XR0 169 
J 0
(-8477 4350);
DISPLAY 0.638298 (-8477 4350);
PAINT MONO (-8477 4350);
FORCEPROP 2 LAST CDS_LIB standard
J 0
(-8225 4350);
DISPLAY INVISIBLE (-8225 4350);
FORCEPROP 1 LAST COMMENT_BODY TRUE
J 0
(-8100 4250);
DISPLAY 0.872340 (-8100 4250);
PAINT GREEN (-8100 4250);
DISPLAY INVISIBLE (-8100 4250);
FORCEPROP 2 LAST PATH I41
J 0
(-8175 4425);
DISPLAY 1.021277 (-8175 4425);
DISPLAY INVISIBLE (-8175 4425);
FORCEPROP 1 LAST OFFPAGE TRUE
J 0
(-7900 4225);
DISPLAY 0.872340 (-7900 4225);
PAINT GREEN (-7900 4225);
DISPLAY INVISIBLE (-7900 4225);
FORCEADD VCC_CORE..1
(-1275 1850);
FORCEPROP 3 LASTPIN (-1275 1800) SIG_NAME PVDDCR_CPU0_P0\g
J 0
(-1265 1810);
DISPLAY 0.659574 (-1265 1810);
PAINT MONO (-1265 1810);
DISPLAY INVISIBLE (-1265 1810);
FORCEPROP 1 LAST HDL_POWER PVDDCR_CPU0_P0
J 1
(-1275 1900);
DISPLAY 0.489362 (-1275 1900);
PAINT GREEN (-1275 1900);
FORCEPROP 2 LAST CDS_LIB pure_quanta_power
J 0
(-1275 1850);
DISPLAY INVISIBLE (-1275 1850);
FORCEPROP 1 LAST PATH I47
J 0
(-1225 1875);
DISPLAY 0.872340 (-1225 1875);
PAINT AQUA (-1225 1875);
DISPLAY INVISIBLE (-1225 1875);
FORCEADD Q_CAP..1
(-1275 1525);
FORCEPROP 1 LAST LOCATION PC501_2
J 0
(-1225 1625);
DISPLAY 0.489362 (-1225 1625);
PAINT SKYBLUE (-1225 1625);
FORCEPROP 0 LAST $SEC 1
J 0
(-1225 1650);
DISPLAY 0.680851 (-1225 1650);
PAINT MONO (-1225 1650);
DISPLAY INVISIBLE (-1225 1650);
FORCEPROP 0 LAST CDS_SEC 1
J 0
(-1225 1650);
DISPLAY 1.021277 (-1225 1650);
DISPLAY INVISIBLE (-1225 1650);
FORCEPROP 1 LASTPIN (-1275 1625) $PN 1
J 0
(-1265 1605);
DISPLAY 0.489362 (-1265 1605);
PAINT MONO (-1265 1605);
FORCEPROP 1 LASTPIN (-1275 1425) $PN 2
J 0
(-1265 1405);
DISPLAY 0.489362 (-1265 1405);
PAINT MONO (-1265 1405);
FORCEPROP 1 LAST MATERIAL X6S
J 0
(-1225 1425);
DISPLAY 0.489362 (-1225 1425);
PAINT SKYBLUE (-1225 1425);
FORCEPROP 1 LAST TOLERANCE 20%
J 0
(-1225 1475);
DISPLAY 0.489362 (-1225 1475);
PAINT SKYBLUE (-1225 1475);
FORCEPROP 1 LAST VALUE 22UF
J 0
(-1225 1575);
DISPLAY 0.489362 (-1225 1575);
PAINT SKYBLUE (-1225 1575);
FORCEPROP 1 LAST PART_NUMBER TMP_QCH622KMEA01
J 0
(-1225 1375);
DISPLAY 0.489362 (-1225 1375);
PAINT SKYBLUE (-1225 1375);
FORCEPROP 1 LAST VOLTAGE 4V
J 0
(-1225 1525);
DISPLAY 0.489362 (-1225 1525);
PAINT SKYBLUE (-1225 1525);
FORCEPROP 1 LAST PACK_TYPE 0805
J 0
(-1225 1325);
DISPLAY 0.489362 (-1225 1325);
PAINT SKYBLUE (-1225 1325);
FORCEPROP 2 LAST CDS_LIB pure_quanta
J 0
(-1275 1525);
DISPLAY INVISIBLE (-1275 1525);
FORCEPROP 1 LAST PATH I48
J 0
(-1225 1675);
DISPLAY 0.978723 (-1225 1675);
PAINT WHITE (-1225 1675);
DISPLAY INVISIBLE (-1225 1675);
FORCEADD UNIVERSAL_GND..1
(-1275 1175);
FORCEPROP 3 LASTPIN (-1275 1225) SIG_NAME GND\g
J 0
(-1265 1235);
DISPLAY 0.659574 (-1265 1235);
PAINT MONO (-1265 1235);
DISPLAY INVISIBLE (-1265 1235);
FORCEPROP 2 LAST CDS_LIB pure_quanta_power
J 0
(-1275 1175);
DISPLAY INVISIBLE (-1275 1175);
FORCEPROP 1 LAST PATH I49
J 0
(-1200 1175);
DISPLAY 0.872340 (-1200 1175);
PAINT AQUA (-1200 1175);
DISPLAY INVISIBLE (-1200 1175);
FORCEPROP 1 LAST HDL_POWER GND
J 1
(-1250 1100);
DISPLAY 0.872340 (-1250 1100);
PAINT GREEN (-1250 1100);
DISPLAY INVISIBLE (-1250 1100);
FORCEADD UNIVERSAL_GND..1
(-7600 5050);
FORCEPROP 3 LASTPIN (-7600 5100) SIG_NAME GND\g
J 0
(-7590 5110);
DISPLAY 0.659574 (-7590 5110);
PAINT MONO (-7590 5110);
DISPLAY INVISIBLE (-7590 5110);
FORCEPROP 2 LAST CDS_LIB pure_quanta_power
J 0
(-7600 5050);
DISPLAY INVISIBLE (-7600 5050);
FORCEPROP 1 LAST PATH I5
J 0
(-7525 5050);
DISPLAY 0.872340 (-7525 5050);
PAINT AQUA (-7525 5050);
DISPLAY INVISIBLE (-7525 5050);
FORCEPROP 1 LAST HDL_POWER GND
J 1
(-7575 4975);
DISPLAY 0.872340 (-7575 4975);
PAINT GREEN (-7575 4975);
DISPLAY INVISIBLE (-7575 4975);
FORCEADD Q_CAP..1
(-1700 1525);
FORCEPROP 1 LAST LOCATION PC499_2
J 0
(-1650 1625);
DISPLAY 0.489362 (-1650 1625);
PAINT SKYBLUE (-1650 1625);
FORCEPROP 0 LAST $SEC 1
J 0
(-1650 1650);
DISPLAY 0.680851 (-1650 1650);
PAINT MONO (-1650 1650);
DISPLAY INVISIBLE (-1650 1650);
FORCEPROP 0 LAST CDS_SEC 1
J 0
(-1650 1650);
DISPLAY 1.021277 (-1650 1650);
DISPLAY INVISIBLE (-1650 1650);
FORCEPROP 1 LASTPIN (-1700 1625) $PN 1
J 0
(-1690 1605);
DISPLAY 0.489362 (-1690 1605);
PAINT MONO (-1690 1605);
FORCEPROP 1 LASTPIN (-1700 1425) $PN 2
J 0
(-1690 1405);
DISPLAY 0.489362 (-1690 1405);
PAINT MONO (-1690 1405);
FORCEPROP 1 LAST MATERIAL X6S
J 0
(-1650 1425);
DISPLAY 0.489362 (-1650 1425);
PAINT SKYBLUE (-1650 1425);
FORCEPROP 1 LAST TOLERANCE 20%
J 0
(-1650 1475);
DISPLAY 0.489362 (-1650 1475);
PAINT SKYBLUE (-1650 1475);
FORCEPROP 1 LAST VALUE 22UF
J 0
(-1650 1575);
DISPLAY 0.489362 (-1650 1575);
PAINT SKYBLUE (-1650 1575);
FORCEPROP 1 LAST PART_NUMBER TMP_QCH622KMEA01
J 0
(-1650 1375);
DISPLAY 0.489362 (-1650 1375);
PAINT SKYBLUE (-1650 1375);
FORCEPROP 1 LAST VOLTAGE 4V
J 0
(-1650 1525);
DISPLAY 0.489362 (-1650 1525);
PAINT SKYBLUE (-1650 1525);
FORCEPROP 1 LAST PACK_TYPE 0805
J 0
(-1650 1325);
DISPLAY 0.489362 (-1650 1325);
PAINT SKYBLUE (-1650 1325);
FORCEPROP 2 LAST CDS_LIB pure_quanta
J 0
(-1700 1525);
DISPLAY INVISIBLE (-1700 1525);
FORCEPROP 1 LAST PATH I50
J 0
(-1650 1675);
DISPLAY 0.978723 (-1650 1675);
PAINT WHITE (-1650 1675);
DISPLAY INVISIBLE (-1650 1675);
FORCEADD VCC_CORE..1
(-4250 2875);
FORCEPROP 3 LASTPIN (-4250 2825) SIG_NAME SW_P12V_STBY_PVDDCR_CPU0_P0_FLT\g
J 0
(-4240 2835);
DISPLAY 0.659574 (-4240 2835);
PAINT MONO (-4240 2835);
DISPLAY INVISIBLE (-4240 2835);
FORCEPROP 1 LAST HDL_POWER SW_P12V_STBY_PVDDCR_CPU0_P0_FLT
J 1
(-4250 2925);
DISPLAY 0.489362 (-4250 2925);
PAINT GREEN (-4250 2925);
FORCEPROP 2 LAST CDS_LIB pure_quanta_power
J 0
(-4250 2875);
DISPLAY INVISIBLE (-4250 2875);
FORCEPROP 1 LAST PATH I54
J 0
(-4200 2900);
DISPLAY 0.872340 (-4200 2900);
PAINT AQUA (-4200 2900);
DISPLAY INVISIBLE (-4200 2900);
FORCEADD UNIVERSAL_GND..1
(-4250 2225);
FORCEPROP 3 LASTPIN (-4250 2275) SIG_NAME GND\g
J 0
(-4240 2285);
DISPLAY 0.659574 (-4240 2285);
PAINT MONO (-4240 2285);
DISPLAY INVISIBLE (-4240 2285);
FORCEPROP 2 LAST CDS_LIB pure_quanta_power
J 0
(-4250 2225);
DISPLAY INVISIBLE (-4250 2225);
FORCEPROP 1 LAST PATH I56
J 0
(-4175 2225);
DISPLAY 0.872340 (-4175 2225);
PAINT AQUA (-4175 2225);
DISPLAY INVISIBLE (-4175 2225);
FORCEPROP 1 LAST HDL_POWER GND
J 1
(-4225 2150);
DISPLAY 0.872340 (-4225 2150);
PAINT GREEN (-4225 2150);
DISPLAY INVISIBLE (-4225 2150);
FORCEADD VCC_CORE..1
(-8600 5925);
FORCEPROP 3 LASTPIN (-8600 5875) SIG_NAME P5V_STBY\g
J 0
(-8590 5885);
DISPLAY 0.659574 (-8590 5885);
PAINT MONO (-8590 5885);
DISPLAY INVISIBLE (-8590 5885);
FORCEPROP 1 LAST HDL_POWER P5V_STBY
J 1
(-8600 5975);
DISPLAY 0.489362 (-8600 5975);
PAINT GREEN (-8600 5975);
FORCEPROP 2 LAST CDS_LIB pure_quanta_power
J 0
(-8600 5925);
DISPLAY INVISIBLE (-8600 5925);
FORCEPROP 1 LAST PATH I6
J 0
(-8550 5950);
DISPLAY 0.872340 (-8550 5950);
PAINT AQUA (-8550 5950);
DISPLAY INVISIBLE (-8550 5950);
FORCEADD Q_CAP..1
(-4250 2575);
FORCEPROP 1 LAST LOCATION PC488_2
J 0
(-4200 2675);
DISPLAY 0.489362 (-4200 2675);
PAINT SKYBLUE (-4200 2675);
FORCEPROP 0 LAST $SEC 1
J 0
(-4200 2700);
DISPLAY 0.680851 (-4200 2700);
PAINT MONO (-4200 2700);
DISPLAY INVISIBLE (-4200 2700);
FORCEPROP 0 LAST CDS_SEC 1
J 0
(-4200 2700);
DISPLAY 1.021277 (-4200 2700);
DISPLAY INVISIBLE (-4200 2700);
FORCEPROP 1 LASTPIN (-4250 2675) $PN 1
J 0
(-4240 2655);
DISPLAY 0.489362 (-4240 2655);
PAINT MONO (-4240 2655);
FORCEPROP 1 LASTPIN (-4250 2475) $PN 2
J 0
(-4240 2455);
DISPLAY 0.489362 (-4240 2455);
PAINT MONO (-4240 2455);
FORCEPROP 1 LAST TOLERANCE 10%
J 0
(-4200 2525);
DISPLAY 0.489362 (-4200 2525);
PAINT SKYBLUE (-4200 2525);
FORCEPROP 1 LAST MATERIAL X6S
J 0
(-4200 2475);
DISPLAY 0.489362 (-4200 2475);
PAINT SKYBLUE (-4200 2475);
FORCEPROP 1 LAST PART_NUMBER CH6104KEA00
J 0
(-4200 2425);
DISPLAY 0.489362 (-4200 2425);
PAINT SKYBLUE (-4200 2425);
FORCEPROP 1 LAST PACK_TYPE C0805
J 0
(-4200 2375);
DISPLAY 0.489362 (-4200 2375);
PAINT SKYBLUE (-4200 2375);
FORCEPROP 1 LAST VALUE 10UF
J 0
(-4200 2625);
DISPLAY 0.489362 (-4200 2625);
PAINT SKYBLUE (-4200 2625);
FORCEPROP 1 LAST VOLTAGE 25V
J 0
(-4200 2575);
DISPLAY 0.489362 (-4200 2575);
PAINT SKYBLUE (-4200 2575);
FORCEPROP 2 LAST CDS_LIB pure_quanta
J 0
(-4250 2575);
DISPLAY INVISIBLE (-4250 2575);
FORCEPROP 1 LAST PATH I62
J 0
(-4200 2725);
DISPLAY 0.978723 (-4200 2725);
PAINT WHITE (-4200 2725);
DISPLAY INVISIBLE (-4200 2725);
FORCEADD Q_INDUCTOR4P_14..1
(-3050 1575);
FORCEPROP 1 LAST LOCATION PL52
J 0
(-3275 1830);
DISPLAY 0.489362 (-3275 1830);
PAINT SKYBLUE (-3275 1830);
FORCEPROP 0 LAST $SEC 1
J 0
(-3275 1975);
DISPLAY 0.680851 (-3275 1975);
PAINT MONO (-3275 1975);
DISPLAY INVISIBLE (-3275 1975);
FORCEPROP 0 LAST CDS_SEC 1
J 0
(-3275 1975);
DISPLAY 1.021277 (-3275 1975);
DISPLAY INVISIBLE (-3275 1975);
FORCEPROP 0 LASTPIN (-3450 1700) $PN 1
J 2
(-3460 1710);
DISPLAY 0.489362 (-3460 1710);
PAINT MONO (-3460 1710);
FORCEPROP 0 LASTPIN (-3450 1450) $PN 2
J 2
(-3460 1460);
DISPLAY 0.489362 (-3460 1460);
PAINT MONO (-3460 1460);
FORCEPROP 0 LASTPIN (-2650 1450) $PN 3
J 0
(-2640 1460);
DISPLAY 0.489362 (-2640 1460);
PAINT MONO (-2640 1460);
FORCEPROP 0 LASTPIN (-2650 1700) $PN 4
J 0
(-2640 1710);
DISPLAY 0.489362 (-2640 1710);
PAINT MONO (-2640 1710);
FORCEPROP 2 LAST PART_TYPE SMLF
J 0
(-3275 1925);
DISPLAY 1.021277 (-3275 1925);
FORCEPROP 1 LAST PART_NUMBER CV+15^0TZ04
J 0
(-3275 1735);
DISPLAY 0.489362 (-3275 1735);
PAINT SKYBLUE (-3275 1735);
FORCEPROP 1 LAST MATERIAL IND
J 0
(-3275 1785);
DISPLAY 0.489362 (-3275 1785);
PAINT SKYBLUE (-3275 1785);
FORCEPROP 2 LAST VALUE 150NH
J 0
(-3275 1875);
DISPLAY 0.489362 (-3275 1875);
PAINT SKYBLUE (-3275 1875);
FORCEPROP 1 LAST NEEDS_NO_SIZE TRUE
J 0
(-3050 1575);
DISPLAY 0.468085 (-3050 1575);
PAINT GREEN (-3050 1575);
DISPLAY INVISIBLE (-3050 1575);
FORCEPROP 2 LAST CDS_LIB pure_quanta
J 0
(-3050 1575);
DISPLAY INVISIBLE (-3050 1575);
FORCEPROP 1 LAST PATH I63
J 0
(-2850 1730);
DISPLAY 0.723404 (-2850 1730);
PAINT GREEN (-2850 1730);
DISPLAY INVISIBLE (-2850 1730);
FORCEADD Q_CAP..1
(-4550 2575);
FORCEPROP 1 LAST LOCATION PC486_2
J 0
(-4500 2675);
DISPLAY 0.489362 (-4500 2675);
PAINT SKYBLUE (-4500 2675);
FORCEPROP 0 LAST $SEC 1
J 0
(-4500 2700);
DISPLAY 0.680851 (-4500 2700);
PAINT MONO (-4500 2700);
DISPLAY INVISIBLE (-4500 2700);
FORCEPROP 0 LAST CDS_SEC 1
J 0
(-4500 2700);
DISPLAY 1.021277 (-4500 2700);
DISPLAY INVISIBLE (-4500 2700);
FORCEPROP 1 LASTPIN (-4550 2675) $PN 1
J 0
(-4540 2655);
DISPLAY 0.489362 (-4540 2655);
PAINT MONO (-4540 2655);
FORCEPROP 1 LASTPIN (-4550 2475) $PN 2
J 0
(-4540 2455);
DISPLAY 0.489362 (-4540 2455);
PAINT MONO (-4540 2455);
FORCEPROP 1 LAST PACK_TYPE C0805
J 0
(-4500 2375);
DISPLAY 0.489362 (-4500 2375);
PAINT SKYBLUE (-4500 2375);
FORCEPROP 1 LAST PART_NUMBER CH6104KEA00
J 0
(-4500 2425);
DISPLAY 0.489362 (-4500 2425);
PAINT SKYBLUE (-4500 2425);
FORCEPROP 1 LAST MATERIAL X6S
J 0
(-4500 2475);
DISPLAY 0.489362 (-4500 2475);
PAINT SKYBLUE (-4500 2475);
FORCEPROP 1 LAST TOLERANCE 10%
J 0
(-4500 2525);
DISPLAY 0.489362 (-4500 2525);
PAINT SKYBLUE (-4500 2525);
FORCEPROP 1 LAST VALUE 10UF
J 0
(-4500 2625);
DISPLAY 0.489362 (-4500 2625);
PAINT SKYBLUE (-4500 2625);
FORCEPROP 1 LAST VOLTAGE 25V
J 0
(-4500 2575);
DISPLAY 0.489362 (-4500 2575);
PAINT SKYBLUE (-4500 2575);
FORCEPROP 2 LAST CDS_LIB pure_quanta
J 0
(-4550 2575);
DISPLAY INVISIBLE (-4550 2575);
FORCEPROP 1 LAST PATH I64
J 0
(-4500 2725);
DISPLAY 0.978723 (-4500 2725);
PAINT WHITE (-4500 2725);
DISPLAY INVISIBLE (-4500 2725);
FORCEADD Q_CAP..1
(-4875 2575);
FORCEPROP 1 LAST LOCATION PC484_2
J 0
(-4825 2675);
DISPLAY 0.489362 (-4825 2675);
PAINT SKYBLUE (-4825 2675);
FORCEPROP 0 LAST $SEC 1
J 0
(-4825 2700);
DISPLAY 0.680851 (-4825 2700);
PAINT MONO (-4825 2700);
DISPLAY INVISIBLE (-4825 2700);
FORCEPROP 0 LAST CDS_SEC 1
J 0
(-4825 2700);
DISPLAY 1.021277 (-4825 2700);
DISPLAY INVISIBLE (-4825 2700);
FORCEPROP 1 LASTPIN (-4875 2675) $PN 1
J 0
(-4865 2655);
DISPLAY 0.489362 (-4865 2655);
PAINT MONO (-4865 2655);
FORCEPROP 1 LASTPIN (-4875 2475) $PN 2
J 0
(-4865 2455);
DISPLAY 0.489362 (-4865 2455);
PAINT MONO (-4865 2455);
FORCEPROP 1 LAST PART_NUMBER CH6104KEA00
J 0
(-4825 2425);
DISPLAY 0.489362 (-4825 2425);
PAINT SKYBLUE (-4825 2425);
FORCEPROP 1 LAST MATERIAL X6S
J 0
(-4825 2475);
DISPLAY 0.489362 (-4825 2475);
PAINT SKYBLUE (-4825 2475);
FORCEPROP 1 LAST TOLERANCE 10%
J 0
(-4825 2525);
DISPLAY 0.489362 (-4825 2525);
PAINT SKYBLUE (-4825 2525);
FORCEPROP 1 LAST VALUE 10UF
J 0
(-4825 2625);
DISPLAY 0.489362 (-4825 2625);
PAINT SKYBLUE (-4825 2625);
FORCEPROP 1 LAST VOLTAGE 25V
J 0
(-4825 2575);
DISPLAY 0.489362 (-4825 2575);
PAINT SKYBLUE (-4825 2575);
FORCEPROP 1 LAST PACK_TYPE C0805
J 0
(-4825 2375);
DISPLAY 0.489362 (-4825 2375);
PAINT SKYBLUE (-4825 2375);
FORCEPROP 2 LAST CDS_LIB pure_quanta
J 0
(-4875 2575);
DISPLAY INVISIBLE (-4875 2575);
FORCEPROP 1 LAST PATH I65
J 0
(-4825 2725);
DISPLAY 0.978723 (-4825 2725);
PAINT WHITE (-4825 2725);
DISPLAY INVISIBLE (-4825 2725);
FORCEADD Q_CAP..1
(-5200 2575);
FORCEPROP 1 LAST LOCATION PC482_2
J 0
(-5150 2675);
DISPLAY 0.489362 (-5150 2675);
PAINT SKYBLUE (-5150 2675);
FORCEPROP 0 LAST $SEC 1
J 0
(-5150 2700);
DISPLAY 0.680851 (-5150 2700);
PAINT MONO (-5150 2700);
DISPLAY INVISIBLE (-5150 2700);
FORCEPROP 0 LAST CDS_SEC 1
J 0
(-5150 2700);
DISPLAY 1.021277 (-5150 2700);
DISPLAY INVISIBLE (-5150 2700);
FORCEPROP 1 LASTPIN (-5200 2675) $PN 1
J 0
(-5190 2655);
DISPLAY 0.489362 (-5190 2655);
PAINT MONO (-5190 2655);
FORCEPROP 1 LASTPIN (-5200 2475) $PN 2
J 0
(-5190 2455);
DISPLAY 0.489362 (-5190 2455);
PAINT MONO (-5190 2455);
FORCEPROP 1 LAST PACK_TYPE C0402
J 0
(-5150 2375);
DISPLAY 0.489362 (-5150 2375);
PAINT SKYBLUE (-5150 2375);
FORCEPROP 1 LAST PART_NUMBER CH5104KEB02
J 0
(-5150 2425);
DISPLAY 0.489362 (-5150 2425);
PAINT SKYBLUE (-5150 2425);
FORCEPROP 1 LAST VALUE 1UF
J 0
(-5150 2625);
DISPLAY 0.489362 (-5150 2625);
PAINT SKYBLUE (-5150 2625);
FORCEPROP 1 LAST MATERIAL X6S
J 0
(-5150 2475);
DISPLAY 0.489362 (-5150 2475);
PAINT SKYBLUE (-5150 2475);
FORCEPROP 1 LAST TOLERANCE 10%
J 0
(-5150 2525);
DISPLAY 0.489362 (-5150 2525);
PAINT SKYBLUE (-5150 2525);
FORCEPROP 1 LAST VOLTAGE 25V
J 0
(-5150 2575);
DISPLAY 0.489362 (-5150 2575);
PAINT SKYBLUE (-5150 2575);
FORCEPROP 2 LAST CDS_LIB pure_quanta
J 0
(-5200 2575);
DISPLAY INVISIBLE (-5200 2575);
FORCEPROP 1 LAST PATH I66
J 0
(-5150 2725);
DISPLAY 0.978723 (-5150 2725);
PAINT WHITE (-5150 2725);
DISPLAY INVISIBLE (-5150 2725);
FORCEADD Q_CAP..1
(-3725 1925);
FORCEPROP 1 LAST LOCATION PC490
J 0
(-3675 2050);
DISPLAY 0.489362 (-3675 2050);
PAINT SKYBLUE (-3675 2050);
FORCEPROP 0 LAST $SEC 1
J 0
(-3675 2075);
DISPLAY 0.680851 (-3675 2075);
PAINT MONO (-3675 2075);
DISPLAY INVISIBLE (-3675 2075);
FORCEPROP 0 LAST CDS_SEC 1
J 0
(-3675 2075);
DISPLAY 1.021277 (-3675 2075);
DISPLAY INVISIBLE (-3675 2075);
FORCEPROP 1 LASTPIN (-3725 2025) $PN 1
J 0
(-3715 2005);
DISPLAY 0.489362 (-3715 2005);
PAINT MONO (-3715 2005);
FORCEPROP 1 LASTPIN (-3725 1825) $PN 2
J 0
(-3715 1805);
DISPLAY 0.489362 (-3715 1805);
PAINT MONO (-3715 1805);
FORCEPROP 1 LAST MATERIAL X7R
J 0
(-3675 1850);
DISPLAY 0.489362 (-3675 1850);
PAINT SKYBLUE (-3675 1850);
FORCEPROP 1 LAST PART_NUMBER CH4223K1B00
J 0
(-3675 1775);
DISPLAY 0.489362 (-3675 1775);
PAINT SKYBLUE (-3675 1775);
FORCEPROP 1 LAST TOLERANCE 10%
J 0
(-3675 1900);
DISPLAY 0.489362 (-3675 1900);
PAINT SKYBLUE (-3675 1900);
FORCEPROP 1 LAST VALUE 0.22UF
J 0
(-3675 2000);
DISPLAY 0.489362 (-3675 2000);
PAINT SKYBLUE (-3675 2000);
FORCEPROP 1 LAST VOLTAGE 16V
J 0
(-3675 1950);
DISPLAY 0.489362 (-3675 1950);
PAINT SKYBLUE (-3675 1950);
FORCEPROP 1 LAST PACK_TYPE 0402
J 0
(-3675 1750);
DISPLAY 0.489362 (-3675 1750);
PAINT SKYBLUE (-3675 1750);
FORCEPROP 2 LAST CDS_LIB pure_quanta
J 0
(-3725 1925);
DISPLAY INVISIBLE (-3725 1925);
FORCEPROP 1 LAST PATH I67
J 0
(-3675 2075);
DISPLAY 0.978723 (-3675 2075);
PAINT WHITE (-3675 2075);
DISPLAY INVISIBLE (-3675 2075);
FORCEADD Q_RES..1
(-4225 775);
FORCEPROP 1 LAST LOCATION PR325
J 0
(-4275 825);
DISPLAY 0.489362 (-4275 825);
PAINT SKYBLUE (-4275 825);
FORCEPROP 0 LAST $SEC 1
J 0
(-4225 850);
DISPLAY 0.680851 (-4225 850);
PAINT MONO (-4225 850);
DISPLAY INVISIBLE (-4225 850);
FORCEPROP 0 LAST CDS_SEC 1
J 0
(-4225 850);
DISPLAY 1.021277 (-4225 850);
DISPLAY INVISIBLE (-4225 850);
FORCEPROP 1 LASTPIN (-4325 775) $PN 1
J 0
(-4313 787);
DISPLAY 0.489362 (-4313 787);
PAINT MONO (-4313 787);
FORCEPROP 1 LASTPIN (-4125 775) $PN 2
J 0
(-4163 787);
DISPLAY 0.489362 (-4163 787);
PAINT MONO (-4163 787);
FORCEPROP 1 LAST WATTAGE 1/16W
J 0
(-4125 725);
DISPLAY 0.489362 (-4125 725);
PAINT SKYBLUE (-4125 725);
FORCEPROP 1 LAST MATERIAL CHIP
J 0
(-4475 675);
DISPLAY 0.489362 (-4475 675);
PAINT SKYBLUE (-4475 675);
FORCEPROP 1 LAST TOLERANCE 5%
J 0
(-4100 800);
DISPLAY 0.489362 (-4100 800);
PAINT SKYBLUE (-4100 800);
FORCEPROP 1 LAST VALUE 0
J 2
(-4350 800);
DISPLAY 0.489362 (-4350 800);
PAINT SKYBLUE (-4350 800);
FORCEPROP 1 LAST PART_NUMBER CS00002JB38
J 0
(-4550 725);
DISPLAY 0.489362 (-4550 725);
PAINT SKYBLUE (-4550 725);
FORCEPROP 1 LAST PACK_TYPE 0402LF
J 0
(-4125 675);
DISPLAY 0.489362 (-4125 675);
PAINT SKYBLUE (-4125 675);
FORCEPROP 2 LAST CDS_LIB pure_quanta
J 0
(-4225 775);
DISPLAY INVISIBLE (-4225 775);
FORCEPROP 1 LAST PATH I68
J 0
(-4275 925);
DISPLAY 0.978723 (-4275 925);
PAINT WHITE (-4275 925);
DISPLAY INVISIBLE (-4275 925);
FORCEADD UNIVERSAL_GND..1
(-7950 4600);
FORCEPROP 3 LASTPIN (-7950 4650) SIG_NAME GND\g
J 0
(-7940 4660);
DISPLAY 0.659574 (-7940 4660);
PAINT MONO (-7940 4660);
DISPLAY INVISIBLE (-7940 4660);
FORCEPROP 2 LAST CDS_LIB pure_quanta_power
J 0
(-7950 4600);
DISPLAY INVISIBLE (-7950 4600);
FORCEPROP 1 LAST PATH I7
J 0
(-7875 4600);
DISPLAY 0.872340 (-7875 4600);
PAINT AQUA (-7875 4600);
DISPLAY INVISIBLE (-7875 4600);
FORCEPROP 1 LAST HDL_POWER GND
J 1
(-7925 4525);
DISPLAY 0.872340 (-7925 4525);
PAINT GREEN (-7925 4525);
DISPLAY INVISIBLE (-7925 4525);
FORCEADD Q_RES..1
(-4700 2050);
FORCEPROP 1 LAST LOCATION PR323
J 0
(-4725 2100);
DISPLAY 0.489362 (-4725 2100);
PAINT SKYBLUE (-4725 2100);
FORCEPROP 0 LAST $SEC 1
J 0
(-4675 2125);
DISPLAY 0.680851 (-4675 2125);
PAINT MONO (-4675 2125);
DISPLAY INVISIBLE (-4675 2125);
FORCEPROP 0 LAST CDS_SEC 1
J 0
(-4675 2125);
DISPLAY 1.021277 (-4675 2125);
DISPLAY INVISIBLE (-4675 2125);
FORCEPROP 1 LASTPIN (-4800 2050) $PN 1
J 0
(-4788 2062);
DISPLAY 0.489362 (-4788 2062);
PAINT MONO (-4788 2062);
FORCEPROP 1 LASTPIN (-4600 2050) $PN 2
J 0
(-4638 2062);
DISPLAY 0.489362 (-4638 2062);
PAINT MONO (-4638 2062);
FORCEPROP 1 LAST PACK_TYPE 0402LF
J 0
(-4600 1950);
DISPLAY 0.489362 (-4600 1950);
PAINT SKYBLUE (-4600 1950);
FORCEPROP 1 LAST MATERIAL CHIP
J 0
(-4950 1950);
DISPLAY 0.489362 (-4950 1950);
PAINT SKYBLUE (-4950 1950);
FORCEPROP 1 LAST WATTAGE 1/16W
J 0
(-4600 2000);
DISPLAY 0.489362 (-4600 2000);
PAINT SKYBLUE (-4600 2000);
FORCEPROP 1 LAST TOLERANCE 1%
J 0
(-4575 2075);
DISPLAY 0.489362 (-4575 2075);
PAINT SKYBLUE (-4575 2075);
FORCEPROP 1 LAST VALUE 4.7
J 2
(-4825 2075);
DISPLAY 0.489362 (-4825 2075);
PAINT SKYBLUE (-4825 2075);
FORCEPROP 1 LAST PART_NUMBER CS-4702FB19
J 0
(-4950 2000);
DISPLAY 0.489362 (-4950 2000);
PAINT SKYBLUE (-4950 2000);
FORCEPROP 1 LAST PATH I71
J 0
(-4750 2200);
DISPLAY 0.978723 (-4750 2200);
PAINT WHITE (-4750 2200);
DISPLAY INVISIBLE (-4750 2200);
FORCEPROP 2 LAST CDS_LIB pure_quanta
J 0
(-4700 2050);
DISPLAY INVISIBLE (-4700 2050);
FORCEADD Q_RES..1
(-7325 1400);
FORCEPROP 1 LAST LOCATION PR321
J 0
(-7375 1450);
DISPLAY 0.489362 (-7375 1450);
PAINT SKYBLUE (-7375 1450);
FORCEPROP 0 LAST $SEC 1
J 0
(-7325 1475);
DISPLAY 0.680851 (-7325 1475);
PAINT MONO (-7325 1475);
DISPLAY INVISIBLE (-7325 1475);
FORCEPROP 0 LAST CDS_SEC 1
J 0
(-7325 1475);
DISPLAY 1.021277 (-7325 1475);
DISPLAY INVISIBLE (-7325 1475);
FORCEPROP 1 LASTPIN (-7425 1400) $PN 1
J 0
(-7413 1412);
DISPLAY 0.489362 (-7413 1412);
PAINT MONO (-7413 1412);
FORCEPROP 1 LASTPIN (-7225 1400) $PN 2
J 0
(-7263 1412);
DISPLAY 0.489362 (-7263 1412);
PAINT MONO (-7263 1412);
FORCEPROP 1 LAST WATTAGE 1/16W
J 0
(-7225 1300);
DISPLAY 0.489362 (-7225 1300);
PAINT SKYBLUE (-7225 1300);
FORCEPROP 1 LAST MATERIAL EMPTY
J 0
(-7525 1300);
DISPLAY 0.489362 (-7525 1300);
PAINT RED (-7525 1300);
FORCEPROP 1 LAST TOLERANCE 1%
J 0
(-7200 1425);
DISPLAY 0.489362 (-7200 1425);
PAINT SKYBLUE (-7200 1425);
FORCEPROP 1 LAST VALUE 8.87K
J 2
(-7425 1425);
DISPLAY 0.489362 (-7425 1425);
PAINT SKYBLUE (-7425 1425);
FORCEPROP 1 LAST PART_NUMBER CS28872FB01
J 0
(-7600 1350);
DISPLAY 0.489362 (-7600 1350);
PAINT SKYBLUE (-7600 1350);
FORCEPROP 1 LAST PACK_TYPE 0402LF
J 0
(-7225 1350);
DISPLAY 0.489362 (-7225 1350);
PAINT SKYBLUE (-7225 1350);
FORCEPROP 2 LAST CDS_LIB pure_quanta
J 0
(-7325 1400);
DISPLAY INVISIBLE (-7325 1400);
FORCEPROP 1 LAST PATH I75
J 0
(-7375 1550);
DISPLAY 0.978723 (-7375 1550);
PAINT WHITE (-7375 1550);
DISPLAY INVISIBLE (-7375 1550);
FORCEADD OFFPAGE..2
R 2
(-7325 4450);
FORCEPROP 2 LAST $XR0 169 
J 0
(-7580 4450);
DISPLAY 0.638298 (-7580 4450);
PAINT MONO (-7580 4450);
FORCEPROP 1 LAST OFFPAGE TRUE
J 2
(-7650 4325);
DISPLAY 0.872340 (-7650 4325);
PAINT GREEN (-7650 4325);
DISPLAY INVISIBLE (-7650 4325);
FORCEPROP 2 LAST CDS_LIB standard
J 2
(-7325 4450);
DISPLAY INVISIBLE (-7325 4450);
FORCEPROP 1 LAST COMMENT_BODY TRUE
J 2
(-7280 4355);
DISPLAY 0.872340 (-7280 4355);
PAINT GREEN (-7280 4355);
DISPLAY INVISIBLE (-7280 4355);
FORCEPROP 2 LAST PATH I8
J 2
(-7375 4525);
DISPLAY 1.021277 (-7375 4525);
DISPLAY INVISIBLE (-7375 4525);
FORCEADD OFFPAGE..2
R 2
(-7300 1700);
FORCEPROP 2 LAST $XR0 169 
J 0
(-7585 1700);
DISPLAY 0.638298 (-7585 1700);
PAINT MONO (-7585 1700);
FORCEPROP 1 LAST OFFPAGE TRUE
J 2
(-7625 1575);
DISPLAY 0.872340 (-7625 1575);
PAINT GREEN (-7625 1575);
DISPLAY INVISIBLE (-7625 1575);
FORCEPROP 2 LAST CDS_LIB standard
J 2
(-7300 1700);
DISPLAY INVISIBLE (-7300 1700);
FORCEPROP 1 LAST COMMENT_BODY TRUE
J 2
(-7255 1605);
DISPLAY 0.872340 (-7255 1605);
PAINT GREEN (-7255 1605);
DISPLAY INVISIBLE (-7255 1605);
FORCEPROP 2 LAST PATH I80
J 0
(-7250 1775);
DISPLAY 1.021277 (-7250 1775);
DISPLAY INVISIBLE (-7250 1775);
FORCEADD OFFPAGE..2
R 2
(-7275 1200);
FORCEPROP 2 LAST $XR3 169 
J 0
(-7800 1164);
DISPLAY 0.638298 (-7800 1164);
PAINT MONO (-7800 1164);
FORCEPROP 2 LAST $XR2 172 
J 0
(-7680 1164);
DISPLAY 0.638298 (-7680 1164);
PAINT MONO (-7680 1164);
FORCEPROP 2 LAST $XR1 171 
J 0
(-7560 1164);
DISPLAY 0.638298 (-7560 1164);
PAINT MONO (-7560 1164);
FORCEPROP 2 LAST $XR0 170 
J 0
(-7560 1200);
DISPLAY 0.638298 (-7560 1200);
PAINT MONO (-7560 1200);
FORCEPROP 1 LAST OFFPAGE TRUE
J 2
(-7600 1075);
DISPLAY 0.872340 (-7600 1075);
PAINT GREEN (-7600 1075);
DISPLAY INVISIBLE (-7600 1075);
FORCEPROP 1 LAST COMMENT_BODY TRUE
J 2
(-7230 1105);
DISPLAY 0.872340 (-7230 1105);
PAINT GREEN (-7230 1105);
DISPLAY INVISIBLE (-7230 1105);
FORCEPROP 2 LAST CDS_LIB standard
J 0
(-7275 1200);
DISPLAY INVISIBLE (-7275 1200);
FORCEPROP 2 LAST PATH I83
J 0
(-7225 1275);
DISPLAY 1.021277 (-7225 1275);
DISPLAY INVISIBLE (-7225 1275);
FORCEADD UNIVERSAL_GND..1
(-7650 1225);
FORCEPROP 3 LASTPIN (-7650 1275) SIG_NAME GND\g
J 0
(-7640 1285);
DISPLAY 0.659574 (-7640 1285);
PAINT MONO (-7640 1285);
DISPLAY INVISIBLE (-7640 1285);
FORCEPROP 2 LAST CDS_LIB pure_quanta_power
J 0
(-7650 1225);
DISPLAY INVISIBLE (-7650 1225);
FORCEPROP 1 LAST PATH I84
J 0
(-7575 1225);
DISPLAY 0.872340 (-7575 1225);
PAINT AQUA (-7575 1225);
DISPLAY INVISIBLE (-7575 1225);
FORCEPROP 1 LAST HDL_POWER GND
J 1
(-7625 1150);
DISPLAY 0.872340 (-7625 1150);
PAINT GREEN (-7625 1150);
DISPLAY INVISIBLE (-7625 1150);
FORCEADD UNIVERSAL_GND..1
(-7975 1150);
FORCEPROP 3 LASTPIN (-7975 1200) SIG_NAME GND\g
J 0
(-7965 1210);
DISPLAY 0.659574 (-7965 1210);
PAINT MONO (-7965 1210);
DISPLAY INVISIBLE (-7965 1210);
FORCEPROP 2 LAST CDS_LIB pure_quanta_power
J 0
(-7975 1150);
DISPLAY INVISIBLE (-7975 1150);
FORCEPROP 1 LAST PATH I85
J 0
(-7900 1150);
DISPLAY 0.872340 (-7900 1150);
PAINT AQUA (-7900 1150);
DISPLAY INVISIBLE (-7900 1150);
FORCEPROP 1 LAST HDL_POWER GND
J 1
(-7950 1075);
DISPLAY 0.872340 (-7950 1075);
PAINT GREEN (-7950 1075);
DISPLAY INVISIBLE (-7950 1075);
FORCEADD Q_CAP..1
(-7975 1425);
FORCEPROP 1 LAST LOCATION PC474_2
J 0
(-7925 1525);
DISPLAY 0.489362 (-7925 1525);
PAINT SKYBLUE (-7925 1525);
FORCEPROP 0 LAST $SEC 1
J 0
(-7925 1550);
DISPLAY 0.680851 (-7925 1550);
PAINT MONO (-7925 1550);
DISPLAY INVISIBLE (-7925 1550);
FORCEPROP 0 LAST CDS_SEC 1
J 0
(-7925 1550);
DISPLAY 1.021277 (-7925 1550);
DISPLAY INVISIBLE (-7925 1550);
FORCEPROP 1 LASTPIN (-7975 1525) $PN 1
J 0
(-7965 1505);
DISPLAY 0.489362 (-7965 1505);
PAINT MONO (-7965 1505);
FORCEPROP 1 LASTPIN (-7975 1325) $PN 2
J 0
(-7965 1305);
DISPLAY 0.489362 (-7965 1305);
PAINT MONO (-7965 1305);
FORCEPROP 1 LAST MATERIAL X7R
J 0
(-7925 1325);
DISPLAY 0.489362 (-7925 1325);
PAINT SKYBLUE (-7925 1325);
FORCEPROP 1 LAST TOLERANCE 10%
J 0
(-7925 1375);
DISPLAY 0.489362 (-7925 1375);
PAINT SKYBLUE (-7925 1375);
FORCEPROP 1 LAST VALUE 0.1UF
J 0
(-7925 1475);
DISPLAY 0.489362 (-7925 1475);
PAINT SKYBLUE (-7925 1475);
FORCEPROP 1 LAST PART_NUMBER CH4104K1B00
J 0
(-7925 1275);
DISPLAY 0.489362 (-7925 1275);
PAINT SKYBLUE (-7925 1275);
FORCEPROP 1 LAST VOLTAGE 25V
J 0
(-7925 1425);
DISPLAY 0.489362 (-7925 1425);
PAINT SKYBLUE (-7925 1425);
FORCEPROP 1 LAST PACK_TYPE 0402
J 0
(-7925 1225);
DISPLAY 0.489362 (-7925 1225);
PAINT SKYBLUE (-7925 1225);
FORCEPROP 2 LAST CDS_LIB pure_quanta
J 0
(-7975 1425);
DISPLAY INVISIBLE (-7975 1425);
FORCEPROP 1 LAST PATH I86
J 0
(-7925 1575);
DISPLAY 0.978723 (-7925 1575);
PAINT WHITE (-7925 1575);
DISPLAY INVISIBLE (-7925 1575);
FORCEADD OFFPAGE..1
(-8200 1600);
FORCEPROP 2 LAST $XR5 175 
J 0
(-9052 1600);
DISPLAY 0.638298 (-9052 1600);
PAINT MONO (-9052 1600);
FORCEPROP 2 LAST $XR4 174 
J 0
(-8932 1600);
DISPLAY 0.638298 (-8932 1600);
PAINT MONO (-8932 1600);
FORCEPROP 2 LAST $XR3 172 
J 0
(-8812 1600);
DISPLAY 0.638298 (-8812 1600);
PAINT MONO (-8812 1600);
FORCEPROP 2 LAST $XR2 171 
J 0
(-8692 1600);
DISPLAY 0.638298 (-8692 1600);
PAINT MONO (-8692 1600);
FORCEPROP 2 LAST $XR1 170 
J 0
(-8572 1600);
DISPLAY 0.638298 (-8572 1600);
PAINT MONO (-8572 1600);
FORCEPROP 2 LAST $XR0 169 
J 0
(-8452 1600);
DISPLAY 0.638298 (-8452 1600);
PAINT MONO (-8452 1600);
FORCEPROP 2 LAST CDS_LIB standard
J 0
(-8200 1600);
DISPLAY INVISIBLE (-8200 1600);
FORCEPROP 1 LAST OFFPAGE TRUE
J 0
(-7875 1475);
DISPLAY 0.872340 (-7875 1475);
PAINT GREEN (-7875 1475);
DISPLAY INVISIBLE (-7875 1475);
FORCEPROP 1 LAST COMMENT_BODY TRUE
J 0
(-8075 1500);
DISPLAY 0.872340 (-8075 1500);
PAINT GREEN (-8075 1500);
DISPLAY INVISIBLE (-8075 1500);
FORCEPROP 2 LAST PATH I87
J 0
(-8150 1675);
DISPLAY 1.021277 (-8150 1675);
DISPLAY INVISIBLE (-8150 1675);
FORCEADD UNIVERSAL_GND..1
(-5600 975);
FORCEPROP 3 LASTPIN (-5600 1025) SIG_NAME GND\g
J 0
(-5590 1035);
DISPLAY 0.659574 (-5590 1035);
PAINT MONO (-5590 1035);
DISPLAY INVISIBLE (-5590 1035);
FORCEPROP 2 LAST CDS_LIB pure_quanta_power
J 0
(-5600 975);
DISPLAY INVISIBLE (-5600 975);
FORCEPROP 1 LAST PATH I88
J 0
(-5525 975);
DISPLAY 0.872340 (-5525 975);
PAINT AQUA (-5525 975);
DISPLAY INVISIBLE (-5525 975);
FORCEPROP 1 LAST HDL_POWER GND
J 1
(-5575 900);
DISPLAY 0.872340 (-5575 900);
PAINT GREEN (-5575 900);
DISPLAY INVISIBLE (-5575 900);
FORCEADD OFFPAGE..1
(-7250 1100);
FORCEPROP 2 LAST $XR0 169 
J 0
(-7532 1100);
DISPLAY 0.638298 (-7532 1100);
PAINT MONO (-7532 1100);
FORCEPROP 2 LAST CDS_LIB standard
J 2
(-7250 1100);
DISPLAY INVISIBLE (-7250 1100);
FORCEPROP 2 LAST PATH I89
J 0
(-7200 1175);
DISPLAY 1.021277 (-7200 1175);
DISPLAY INVISIBLE (-7200 1175);
FORCEPROP 1 LAST OFFPAGE TRUE
J 0
(-6925 975);
DISPLAY 0.872340 (-6925 975);
PAINT GREEN (-6925 975);
DISPLAY INVISIBLE (-6925 975);
FORCEPROP 1 LAST COMMENT_BODY TRUE
J 0
(-7125 1000);
DISPLAY 0.872340 (-7125 1000);
PAINT GREEN (-7125 1000);
DISPLAY INVISIBLE (-7125 1000);
FORCEADD OFFPAGE..2
R 2
(-7300 3950);
FORCEPROP 2 LAST $XR3 169 
J 0
(-7825 3914);
DISPLAY 0.638298 (-7825 3914);
PAINT MONO (-7825 3914);
FORCEPROP 2 LAST $XR2 172 
J 0
(-7705 3914);
DISPLAY 0.638298 (-7705 3914);
PAINT MONO (-7705 3914);
FORCEPROP 2 LAST $XR1 171 
J 0
(-7585 3914);
DISPLAY 0.638298 (-7585 3914);
PAINT MONO (-7585 3914);
FORCEPROP 2 LAST $XR0 170 
J 0
(-7585 3950);
DISPLAY 0.638298 (-7585 3950);
PAINT MONO (-7585 3950);
FORCEPROP 1 LAST OFFPAGE TRUE
J 2
(-7625 3825);
DISPLAY 0.872340 (-7625 3825);
PAINT GREEN (-7625 3825);
DISPLAY INVISIBLE (-7625 3825);
FORCEPROP 2 LAST CDS_LIB standard
J 0
(-7300 3950);
DISPLAY INVISIBLE (-7300 3950);
FORCEPROP 1 LAST COMMENT_BODY TRUE
J 2
(-7255 3855);
DISPLAY 0.872340 (-7255 3855);
PAINT GREEN (-7255 3855);
DISPLAY INVISIBLE (-7255 3855);
FORCEPROP 2 LAST PATH I9
J 0
(-7250 4025);
DISPLAY 1.021277 (-7250 4025);
DISPLAY INVISIBLE (-7250 4025);
FORCEADD OFFPAGE..3
R 2
(-3925 1450);
FORCEPROP 2 LAST $XR0 170 
J 0
(-4205 1450);
DISPLAY 0.638298 (-4205 1450);
PAINT MONO (-4205 1450);
FORCEPROP 1 LAST OFFPAGE TRUE
J 2
(-4250 1325);
DISPLAY 0.872340 (-4250 1325);
PAINT GREEN (-4250 1325);
DISPLAY INVISIBLE (-4250 1325);
FORCEPROP 2 LAST PATH I91
J 2
(-4125 1525);
DISPLAY 1.021277 (-4125 1525);
DISPLAY INVISIBLE (-4125 1525);
FORCEPROP 2 LAST CDS_LIB standard
J 2
(-3925 1450);
DISPLAY INVISIBLE (-3925 1450);
FORCEPROP 1 LAST COMMENT_BODY TRUE
J 2
(-3875 1350);
DISPLAY 0.872340 (-3875 1350);
PAINT GREEN (-3875 1350);
DISPLAY INVISIBLE (-3875 1350);
FORCEADD Q_CAPP..1
(-2150 2900);
FORCEPROP 1 LAST LOCATION PC496
J 0
(-2100 3000);
DISPLAY 0.489362 (-2100 3000);
PAINT SKYBLUE (-2100 3000);
FORCEPROP 0 LAST $SEC 1
J 0
(-2100 3025);
DISPLAY 0.680851 (-2100 3025);
PAINT MONO (-2100 3025);
DISPLAY INVISIBLE (-2100 3025);
FORCEPROP 0 LAST CDS_SEC 1
J 0
(-2100 3025);
DISPLAY 1.021277 (-2100 3025);
DISPLAY INVISIBLE (-2100 3025);
FORCEPROP 1 LASTPIN (-2150 3000) $PN 1
J 0
(-2140 2985);
DISPLAY 0.489362 (-2140 2985);
PAINT MONO (-2140 2985);
FORCEPROP 1 LASTPIN (-2150 2800) $PN 2
J 0
(-2140 2785);
DISPLAY 0.489362 (-2140 2785);
PAINT MONO (-2140 2785);
FORCEPROP 1 LAST VALUE 220UF
J 0
(-2100 2950);
DISPLAY 0.489362 (-2100 2950);
PAINT SKYBLUE (-2100 2950);
FORCEPROP 1 LAST VOLTAGE 4V
J 0
(-2100 2850);
DISPLAY 0.489362 (-2100 2850);
PAINT SKYBLUE (-2100 2850);
FORCEPROP 1 LAST TOLERANCE 20%
J 0
(-2100 2900);
DISPLAY 0.489362 (-2100 2900);
PAINT SKYBLUE (-2100 2900);
FORCEPROP 1 LAST PACK_TYPE SMLF
J 0
(-2100 2750);
DISPLAY 0.489362 (-2100 2750);
PAINT SKYBLUE (-2100 2750);
FORCEPROP 1 LAST MATERIAL SPCAP
J 0
(-2100 2800);
DISPLAY 0.489362 (-2100 2800);
PAINT SKYBLUE (-2100 2800);
FORCEPROP 1 LAST PART_NUMBER CH122KM8801
J 0
(-2100 2700);
DISPLAY 0.489362 (-2100 2700);
PAINT SKYBLUE (-2100 2700);
FORCEPROP 1 LAST PATH I92
J 0
(-2100 3050);
DISPLAY 0.978723 (-2100 3050);
DISPLAY INVISIBLE (-2100 3050);
FORCEPROP 2 LAST CDS_LIB pure_quanta
J 0
(-2150 2900);
DISPLAY INVISIBLE (-2150 2900);
FORCEADD DNS..1
(-4825 4275);
PAINT RED (-4825 4275);
FORCEPROP 2 LAST CDS_LIB mstr_misc
J 0
(-4825 4275);
DISPLAY INVISIBLE (-4825 4275);
FORCEPROP 1 LAST COMMENT_BODY TRUE
R 1
J 0
(-4750 4050);
DISPLAY 0.872340 (-4750 4050);
PAINT GREEN (-4750 4050);
DISPLAY INVISIBLE (-4750 4050);
FORCEADD DNS..1
(-7325 1375);
PAINT RED (-7325 1375);
FORCEPROP 2 LAST CDS_LIB mstr_misc
J 0
(-7325 1375);
DISPLAY INVISIBLE (-7325 1375);
FORCEPROP 1 LAST COMMENT_BODY TRUE
R 1
J 0
(-7250 1150);
DISPLAY 0.872340 (-7250 1150);
PAINT GREEN (-7250 1150);
DISPLAY INVISIBLE (-7250 1150);
FORCEADD DNS..1
(-4650 1525);
PAINT RED (-4650 1525);
FORCEPROP 2 LAST CDS_LIB mstr_misc
J 0
(-4650 1525);
DISPLAY INVISIBLE (-4650 1525);
FORCEPROP 1 LAST COMMENT_BODY TRUE
R 1
J 0
(-4575 1300);
DISPLAY 0.872340 (-4575 1300);
PAINT GREEN (-4575 1300);
DISPLAY INVISIBLE (-4575 1300);
FORCEADD DNS..1
(-8250 5750);
PAINT RED (-8250 5750);
FORCEPROP 2 LAST CDS_LIB mstr_misc
J 0
(-8250 5750);
DISPLAY INVISIBLE (-8250 5750);
FORCEPROP 1 LAST COMMENT_BODY TRUE
R 1
J 0
(-8175 5525);
DISPLAY 0.872340 (-8175 5525);
PAINT GREEN (-8175 5525);
DISPLAY INVISIBLE (-8175 5525);
FORCEADD QUANTA_TITLE_BLOCK_C..1
(0 0);
FORCEPROP 0 LAST CDS_CON_LAST_MODIFIED Fri Mar 11 14:53:24 2022
J 0
(-1885 15);
DISPLAY INVISIBLE (-1885 15);
FORCEPROP 1 LAST CUSTOM_TXT_CDS <CON_LAST_MODIFIED>
J 0
(-1885 15);
DISPLAY 0.978723 (-1885 15);
FORCEPROP 2 LAST CUSTOM_TXT_CDS <XR_PAGE_TITLE>
J 0
(-7890 5250);
DISPLAY 0.638298 (-7890 5250);
PAINT PINK (-7890 5250);
DISPLAY INVISIBLE (-7890 5250);
FORCEPROP 1 LAST CUSTOM_TXT_CDS <NAME_2>
J 0
(-3175 50);
FORCEPROP 1 LAST CUSTOM_TXT_CDS <NAME_1>
J 0
(-3175 175);
FORCEPROP 1 LAST CUSTOM_TXT_CDS <Q_NUMBER>
J 0
(-1403 103);
DISPLAY 1.212766 (-1403 103);
FORCEPROP 1 LAST CUSTOM_TXT_CDS <Q_PROJ>
J 0
(-2382 102);
DISPLAY 1.212766 (-2382 102);
FORCEPROP 1 LAST CUSTOM_TXT_CDS <Q_REV>
J 0
(-184 103);
DISPLAY 1.212766 (-184 103);
FORCEPROP 1 LAST CUSTOM_TXT_CDS <CON_PAGE_NUM> OF <CON_TOTAL_PAGES>
J 0
(-446 18);
DISPLAY 0.978723 (-446 18);
FORCEPROP 1 LAST Q_TITLE PVDDCR_CPU0_P0 VR PHASE 1&2
J 0
(-9325 50);
DISPLAY 2.446809 (-9325 50);
PAINT GREEN (-9325 50);
FORCEPROP 1 LAST Q_DEPT BU9
J 1
(-3763 49);
DISPLAY 1.957447 (-3763 49);
PAINT GREEN (-3763 49);
FORCEPROP 2 LAST PAGE_BORDER TRUE
J 0
(-7890 5250);
DISPLAY 0.638298 (-7890 5250);
PAINT PINK (-7890 5250);
DISPLAY INVISIBLE (-7890 5250);
FORCEPROP 1 LAST CDS_LMAN_SYM_OUTLINE -9475,6775,100,-125
J 0
(0 0);
DISPLAY 0.468085 (0 0);
PAINT GREEN (0 0);
DISPLAY INVISIBLE (0 0);
FORCEPROP 2 LAST CDS_LIB pure_quanta
J 0
(0 0);
DISPLAY INVISIBLE (0 0);
FORCEPROP 1 LAST COMMENT_BODY TRUE
J 0
(12 -13);
DISPLAY 0.978723 (12 -13);
PAINT GREEN (12 -13);
DISPLAY INVISIBLE (12 -13);
FORCEPROP 2 LAST CDS_XR_PAGE_TITLE CR-170 : @T6G_MB_LIB.T6G(SCH_1):PAGE170
J 0
(-7890 5250);
DISPLAY 0.638298 (-7890 5250);
PAINT PINK (-7890 5250);
DISPLAY INVISIBLE (-7890 5250);
FORCEADD DNS..1
(-4650 1075);
PAINT RED (-4650 1075);
FORCEPROP 2 LAST CDS_LIB mstr_misc
J 0
(-4650 1075);
DISPLAY INVISIBLE (-4650 1075);
FORCEPROP 1 LAST COMMENT_BODY TRUE
R 1
J 0
(-4575 850);
DISPLAY 0.872340 (-4575 850);
PAINT GREEN (-4575 850);
DISPLAY INVISIBLE (-4575 850);
FORCEADD DNS..1
(-4825 3825);
PAINT RED (-4825 3825);
FORCEPROP 2 LAST CDS_LIB mstr_misc
J 0
(-4825 3825);
DISPLAY INVISIBLE (-4825 3825);
FORCEPROP 1 LAST COMMENT_BODY TRUE
R 1
J 0
(-4750 3600);
DISPLAY 0.872340 (-4750 3600);
PAINT GREEN (-4750 3600);
DISPLAY INVISIBLE (-4750 3600);
FORCEADD DNS..1
(-7325 4125);
PAINT RED (-7325 4125);
FORCEPROP 2 LAST CDS_LIB mstr_misc
J 0
(-7325 4125);
DISPLAY INVISIBLE (-7325 4125);
FORCEPROP 1 LAST COMMENT_BODY TRUE
R 1
J 0
(-7250 3900);
DISPLAY 0.872340 (-7250 3900);
PAINT GREEN (-7250 3900);
DISPLAY INVISIBLE (-7250 3900);
WIRE 16 -1 (-7625 1950)(-7625 1900);
WIRE 16 -1 (-7275 2475)(-7275 2350);
WIRE 16 -1 (-7425 4150)(-7650 4150);
WIRE 16 -1 (-7650 4150)(-7650 4025);
WIRE 16 -1 (-4800 3725)(-4800 3650);
WIRE 16 -1 (-4625 975)(-4625 900);
WIRE 16 -1 (-8250 5875)(-8250 5825);
WIRE 16 -1 (-8000 4075)(-8000 3950);
WIRE 16 -1 (-7600 5200)(-7600 5100);
WIRE 16 -1 (-8600 5875)(-8600 5825);
WIRE 16 -1 (-7950 4700)(-7950 4650);
WIRE 16 -1 (-7425 1400)(-7650 1400);
WIRE 16 -1 (-7650 1400)(-7650 1275);
WIRE 16 -1 (-7975 1325)(-7975 1200);
WIRE 17 273 (-1400 2325)(-1400 3425);
WIRE 17 273 (-3325 2325)(-1400 2325);
WIRE 17 273 (-1400 3425)(-3325 3425);
WIRE 17 273 (-3325 3425)(-3325 2325);
WIRE 16 -1 (-1850 3150)(-1850 3100);
WIRE 16 -1 (-1875 3100)(-1850 3100);
WIRE 16 -1 (-1875 3000)(-1875 3100);
WIRE 16 -1 (-1875 3100)(-2150 3100);
WIRE 16 -1 (-2150 3000)(-2150 3100);
WIRE 16 -1 (-2475 3100)(-2150 3100);
WIRE 16 -1 (-2475 3000)(-2475 3100);
WIRE 16 -1 (-2800 3100)(-2475 3100);
WIRE 16 -1 (-2800 3000)(-2800 3100);
WIRE 16 -1 (-3150 3100)(-2800 3100);
WIRE 16 -1 (-3150 3000)(-3150 3100);
WIRE 16 -1 (-1850 2575)(-1850 2650);
WIRE 16 -1 (-1875 2650)(-1850 2650);
WIRE 16 -1 (-1875 2800)(-1875 2650);
WIRE 16 -1 (-1875 2650)(-2150 2650);
WIRE 16 -1 (-2150 2650)(-2150 2800);
WIRE 16 -1 (-2475 2650)(-2150 2650);
WIRE 16 -1 (-2475 2800)(-2475 2650);
WIRE 16 -1 (-2800 2650)(-2475 2650);
WIRE 16 -1 (-2800 2800)(-2800 2650);
WIRE 16 -1 (-3150 2650)(-2800 2650);
WIRE 16 -1 (-3150 2800)(-3150 2650);
WIRE 16 -1 (-3725 1825)(-3725 1800);
WIRE 16 -1 (-3725 1800)(-5750 1800);
FORCEPROP 2 LAST SIG_NAME SW_PVDDCR_CPU0_P0_PH2
J 0
(-5635 1810);
DISPLAY 0.489362 (-5635 1810);
FORCEPROP 2 LASTPROP $XRERR UNIQUE?
J 0
(-5875 1810);
DISPLAY 0.638298 (-5875 1810);
PAINT MONO (-5875 1810);
DISPLAY INVISIBLE (-5875 1810);
WIRE 16 -1 (-5750 1700)(-4625 1700);
FORCEPROP 2 LAST SIG_NAME SW_PVDDCR_CPU0_P0_SW2
J 0
(-5635 1710);
DISPLAY 0.489362 (-5635 1710);
FORCEPROP 2 LASTPROP $XRERR UNIQUE?
J 0
(-5875 1710);
DISPLAY 0.638298 (-5875 1710);
PAINT MONO (-5875 1710);
DISPLAY INVISIBLE (-5875 1710);
WIRE 16 -1 (-4625 1700)(-3450 1700);
WIRE 16 -1 (-4625 1700)(-4625 1625);
WIRE 16 -1 (-5750 2050)(-4800 2050);
FORCEPROP 2 LAST SIG_NAME SW_PVDDCR_CPU0_P0_BOOT2
J 0
(-5635 2060);
DISPLAY 0.489362 (-5635 2060);
FORCEPROP 2 LASTPROP $XRERR UNIQUE?
J 0
(-5875 2060);
DISPLAY 0.638298 (-5875 2060);
PAINT MONO (-5875 2060);
DISPLAY INVISIBLE (-5875 2060);
WIRE 16 -1 (-5650 2350)(-5650 2300);
WIRE 16 -1 (-5650 2750)(-5650 2350);
WIRE 16 -1 (-5750 2350)(-5650 2350);
WIRE 16 -1 (-5650 2300)(-5750 2300);
WIRE 16 -1 (-5650 2750)(-5525 2750);
WIRE 16 -1 (-5525 2750)(-5200 2750);
WIRE 16 -1 (-5525 2675)(-5525 2750);
WIRE 16 -1 (-5200 2750)(-4875 2750);
WIRE 16 -1 (-5200 2675)(-5200 2750);
WIRE 16 -1 (-4875 2750)(-4550 2750);
WIRE 16 -1 (-4875 2675)(-4875 2750);
WIRE 16 -1 (-4550 2750)(-4250 2750);
WIRE 16 -1 (-4550 2750)(-4550 2675);
WIRE 16 -1 (-4250 2825)(-4250 2750);
WIRE 16 -1 (-4250 2750)(-4250 2675);
WIRE 16 -1 (-3500 5225)(-3500 5100);
WIRE 16 -1 (-3500 5100)(-3925 5100);
WIRE 16 -1 (-3925 5225)(-3925 5100);
WIRE 16 -1 (-4000 5100)(-3925 5100);
WIRE 16 -1 (-4000 5100)(-4000 5050);
WIRE 16 -1 (-4250 5100)(-4000 5100);
WIRE 16 -1 (-4250 5225)(-4250 5100);
WIRE 16 -1 (-4250 5100)(-4550 5100);
WIRE 16 -1 (-4550 5225)(-4550 5100);
WIRE 16 -1 (-4875 5100)(-4550 5100);
WIRE 16 -1 (-4875 5225)(-4875 5100);
WIRE 16 -1 (-5200 5100)(-4875 5100);
WIRE 16 -1 (-5200 5225)(-5200 5100);
WIRE 16 -1 (-5525 5100)(-5200 5100);
WIRE 16 -1 (-5525 5100)(-5525 5225);
WIRE 16 -1 (-4800 4450)(-3625 4450);
WIRE 16 -1 (-4800 4450)(-4800 4375);
WIRE 16 -1 (-5775 4450)(-4800 4450);
FORCEPROP 2 LAST SIG_NAME SW_PVDDCR_CPU0_P0_SW1
J 0
(-5660 4460);
DISPLAY 0.489362 (-5660 4460);
FORCEPROP 2 LASTPROP $XRERR UNIQUE?
J 0
(-5900 4460);
DISPLAY 0.638298 (-5900 4460);
PAINT MONO (-5900 4460);
DISPLAY INVISIBLE (-5900 4460);
WIRE 16 -1 (-3975 4575)(-3975 4550);
WIRE 16 -1 (-3975 4550)(-5775 4550);
FORCEPROP 2 LAST SIG_NAME SW_PVDDCR_CPU0_P0_PH1
J 0
(-5660 4560);
DISPLAY 0.489362 (-5660 4560);
FORCEPROP 2 LASTPROP $XRERR UNIQUE?
J 0
(-5900 4560);
DISPLAY 0.638298 (-5900 4560);
PAINT MONO (-5900 4560);
DISPLAY INVISIBLE (-5900 4560);
WIRE 16 -1 (-2750 5550)(-2750 5500);
WIRE 16 -1 (-2750 5500)(-2950 5500);
WIRE 16 -1 (-4725 4800)(-3975 4800);
FORCEPROP 2 LAST SIG_NAME SW_PVDDCR_CPU0_P0_BOOT1_RC
J 2
(-4010 4810);
DISPLAY 0.489362 (-4010 4810);
FORCEPROP 2 LASTPROP $XRERR UNIQUE?
J 0
(-4250 4810);
DISPLAY 0.638298 (-4250 4810);
PAINT MONO (-4250 4810);
DISPLAY INVISIBLE (-4250 4810);
WIRE 16 -1 (-3975 4800)(-3975 4775);
WIRE 16 -1 (-750 3950)(-750 4050);
WIRE 16 -1 (-750 4150)(-750 4050);
WIRE 16 -1 (-750 4050)(-1150 4050);
WIRE 16 -1 (-1150 4175)(-1150 4050);
WIRE 16 -1 (-1150 4050)(-1600 4050);
WIRE 16 -1 (-1600 4175)(-1600 4050);
WIRE 16 -1 (-1975 4050)(-1600 4050);
WIRE 16 -1 (-1975 4050)(-1975 4175);
WIRE 16 -1 (-1700 1425)(-1700 1300);
WIRE 16 -1 (-1275 1300)(-1700 1300);
WIRE 16 -1 (-1275 1425)(-1275 1300);
WIRE 16 -1 (-1275 1225)(-1275 1300);
WIRE 16 -1 (-2200 1450)(-2650 1450);
FORCEPROP 2 LAST SIG_NAME IND_CPU0_P0_CPL2
J 0
(-2585 1460);
DISPLAY 0.489362 (-2585 1460);
WIRE 16 -1 (-5775 4100)(-5250 4100);
FORCEPROP 2 LAST SIG_NAME NC_PVDDCR_CPU0_P0_GL2_1
J 0
(-5650 4110);
DISPLAY 0.489362 (-5650 4110);
FORCEPROP 2 LASTPROP $XRERR UNIQUE?
J 0
(-5220 4100);
DISPLAY 0.638298 (-5220 4100);
PAINT MONO (-5220 4100);
DISPLAY INVISIBLE (-5220 4100);
WIRE 16 -1 (-5775 4150)(-5250 4150);
FORCEPROP 2 LAST SIG_NAME NC_PVDDCR_CPU0_P0_GL1_1
J 0
(-5650 4160);
DISPLAY 0.489362 (-5650 4160);
FORCEPROP 2 LASTPROP $XRERR UNIQUE?
J 0
(-5220 4150);
DISPLAY 0.638298 (-5220 4150);
PAINT MONO (-5220 4150);
DISPLAY INVISIBLE (-5220 4150);
WIRE 16 -1 (-6625 4450)(-7275 4450);
FORCEPROP 2 LAST SIG_NAME PVDDCR_CPU0_P0_IMON1
J 2
(-6685 4460);
DISPLAY 0.489362 (-6685 4460);
WIRE 16 -1 (-7950 5200)(-7950 4975);
WIRE 16 -1 (-7200 4975)(-7950 4975);
WIRE 16 -1 (-7950 4975)(-7950 4900);
WIRE 16 -1 (-7200 4975)(-7200 4800);
FORCEPROP 2 LAST SIG_NAME PVDDCR_CPU0_P0_VCC1
J 2
(-6735 4810);
DISPLAY 0.489362 (-6735 4810);
FORCEPROP 2 LASTPROP $XRERR UNIQUE?
J 0
(-6975 4810);
DISPLAY 0.638298 (-6975 4810);
PAINT MONO (-6975 4810);
DISPLAY INVISIBLE (-6975 4810);
WIRE 16 -1 (-7200 4800)(-6625 4800);
WIRE 16 -1 (-7200 4800)(-7200 4600);
WIRE 16 -1 (-7200 4600)(-6625 4600);
WIRE 16 -1 (-4800 4175)(-4800 3925);
FORCEPROP 2 LAST SIG_NAME SW_PVDDCR_CPU0_P0_SW1_RC
J 0
(-4760 4010);
DISPLAY 0.489362 (-4760 4010);
FORCEPROP 2 LASTPROP $XRERR UNIQUE?
J 0
(-5000 4010);
DISPLAY 0.638298 (-5000 4010);
PAINT MONO (-5000 4010);
DISPLAY INVISIBLE (-5000 4010);
WIRE 16 -1 (-4450 3500)(-5025 3500);
FORCEPROP 2 LAST SIG_NAME PVDDCR_CPU0_P0_VOS1
J 0
(-5660 4225);
DISPLAY 0.489362 (-5660 4225);
FORCEPROP 2 LASTPROP $XRERR UNIQUE?
J 0
(-5900 4225);
DISPLAY 0.638298 (-5900 4225);
PAINT MONO (-5900 4225);
DISPLAY INVISIBLE (-5900 4225);
WIRE 16 -1 (-5025 3500)(-5025 4200);
WIRE 16 -1 (-5775 4200)(-5025 4200);
WIRE 16 -1 (-5775 3850)(-5600 3850);
WIRE 16 -1 (-5600 3850)(-5600 3900);
WIRE 16 -1 (-5600 3775)(-5600 3850);
WIRE 16 -1 (-5775 3900)(-5600 3900);
WIRE 16 -1 (-5600 3900)(-5600 3950);
WIRE 16 -1 (-5775 3950)(-5600 3950);
WIRE 16 -1 (-5600 4000)(-5600 3950);
WIRE 16 -1 (-5600 4000)(-5775 4000);
WIRE 16 -1 (-4625 1425)(-4625 1175);
FORCEPROP 2 LAST SIG_NAME SW_PVDDCR_CPU0_P0_SW2_RC
J 0
(-4585 1260);
DISPLAY 0.489362 (-4585 1260);
FORCEPROP 2 LASTPROP $XRERR UNIQUE?
J 0
(-4825 1260);
DISPLAY 0.638298 (-4825 1260);
PAINT MONO (-4825 1260);
DISPLAY INVISIBLE (-4825 1260);
WIRE 16 -1 (-5750 1100)(-5600 1100);
WIRE 16 -1 (-5600 1025)(-5600 1100);
WIRE 16 -1 (-5600 1100)(-5600 1150);
WIRE 16 -1 (-5750 1150)(-5600 1150);
WIRE 16 -1 (-5600 1150)(-5600 1200);
WIRE 16 -1 (-5750 1200)(-5600 1200);
WIRE 16 -1 (-5600 1250)(-5600 1200);
WIRE 16 -1 (-5600 1250)(-5750 1250);
WIRE 16 -1 (-5750 1400)(-5225 1400);
FORCEPROP 2 LAST SIG_NAME NC_PVDDCR_CPU0_P0_GL1_2
J 0
(-5635 1410);
DISPLAY 0.489362 (-5635 1410);
FORCEPROP 2 LASTPROP $XRERR UNIQUE?
J 0
(-5195 1400);
DISPLAY 0.638298 (-5195 1400);
PAINT MONO (-5195 1400);
DISPLAY INVISIBLE (-5195 1400);
WIRE 16 -1 (-5750 1350)(-5225 1350);
FORCEPROP 2 LAST SIG_NAME NC_PVDDCR_CPU0_P0_GL2_2
J 0
(-5635 1360);
DISPLAY 0.489362 (-5635 1360);
FORCEPROP 2 LASTPROP $XRERR UNIQUE?
J 0
(-5195 1350);
DISPLAY 0.638298 (-5195 1350);
PAINT MONO (-5195 1350);
DISPLAY INVISIBLE (-5195 1350);
WIRE 16 -1 (-7625 2650)(-7625 2775);
WIRE 16 -1 (-7275 2775)(-7625 2775);
WIRE 16 -1 (-7625 2900)(-7625 2775);
WIRE 16 -1 (-6950 2775)(-7275 2775);
WIRE 16 -1 (-7275 2675)(-7275 2775);
WIRE 16 -1 (-6950 2350)(-6950 2775);
WIRE 16 -1 (-6950 2350)(-6600 2350);
WIRE 16 -1 (-7150 2050)(-7150 1850);
WIRE 16 -1 (-7150 2050)(-6600 2050);
WIRE 16 -1 (-7150 2225)(-7150 2050);
FORCEPROP 2 LAST SIG_NAME PVDDCR_CPU0_P0_VCC2
J 2
(-6685 2060);
DISPLAY 0.489362 (-6685 2060);
FORCEPROP 2 LASTPROP $XRERR UNIQUE?
J 0
(-6925 2060);
DISPLAY 0.638298 (-6925 2060);
PAINT MONO (-6925 2060);
DISPLAY INVISIBLE (-6925 2060);
WIRE 16 -1 (-7150 1850)(-6600 1850);
WIRE 16 -1 (-7625 2225)(-7150 2225);
WIRE 16 -1 (-7625 2450)(-7625 2225);
WIRE 16 -1 (-7625 2225)(-7625 2150);
WIRE 16 -1 (-6600 1450)(-7050 1450);
FORCEPROP 2 LAST SIG_NAME NC_PVDDCR_CPU0_P0_DNC2
J 2
(-6660 1460);
DISPLAY 0.489362 (-6660 1460);
FORCEPROP 2 LASTPROP $XRERR UNIQUE?
J 0
(-7290 1450);
DISPLAY 0.638298 (-7290 1450);
PAINT MONO (-7290 1450);
DISPLAY INVISIBLE (-7290 1450);
WIRE 16 -1 (-6600 1100)(-7200 1100);
FORCEPROP 2 LAST SIG_NAME PVDDCR_CPU0_P0_PWM2
J 2
(-6685 1110);
DISPLAY 0.489362 (-6685 1110);
WIRE 16 -1 (-6600 1200)(-7225 1200);
FORCEPROP 2 LAST SIG_NAME PVDDCR_CPU0_P0_TEMP0
J 2
(-6660 1210);
DISPLAY 0.489362 (-6660 1210);
WIRE 16 -1 (-6600 1700)(-7250 1700);
FORCEPROP 2 LAST SIG_NAME PVDDCR_CPU0_P0_IMON2
J 2
(-6660 1710);
DISPLAY 0.489362 (-6660 1710);
WIRE 16 -1 (-7225 1400)(-6600 1400);
FORCEPROP 2 LAST SIG_NAME PVDDCR_CPU0_P0_LSET2
J 2
(-6660 1410);
DISPLAY 0.489362 (-6660 1410);
FORCEPROP 2 LASTPROP $XRERR UNIQUE?
J 0
(-6900 1410);
DISPLAY 0.638298 (-6900 1410);
PAINT MONO (-6900 1410);
DISPLAY INVISIBLE (-6900 1410);
WIRE 16 -1 (-7975 1525)(-7975 1600);
WIRE 16 -1 (-6600 1600)(-7975 1600);
FORCEPROP 2 LAST SIG_NAME PVDDCR_CPU0_P0_VCCS
J 2
(-6660 1610);
DISPLAY 0.489362 (-6660 1610);
WIRE 16 -1 (-8150 1600)(-7975 1600);
WIRE 16 -1 (-8600 5625)(-8600 5550);
WIRE 16 -1 (-8600 5550)(-8250 5550);
WIRE 16 -1 (-7950 5550)(-8250 5550);
WIRE 16 -1 (-8250 5625)(-8250 5550);
WIRE 16 -1 (-7775 5550)(-7950 5550);
WIRE 16 -1 (-7950 5400)(-7950 5550);
WIRE 16 -1 (-7775 5550)(-7600 5550);
WIRE 16 -1 (-7775 5875)(-7775 5550);
WIRE 16 -1 (-6975 5550)(-7600 5550);
WIRE 16 -1 (-7600 5400)(-7600 5550);
WIRE 16 -1 (-6975 5100)(-6975 5550);
WIRE 16 -1 (-6975 5100)(-6625 5100);
WIRE 16 -1 (-2825 4200)(-2350 4200);
FORCEPROP 2 LAST SIG_NAME IND_CPU0_P0_CPL1
J 0
(-2760 4210);
DISPLAY 0.489362 (-2760 4210);
WIRE 16 -1 (-1900 1700)(-1900 775);
WIRE 16 -1 (-2650 1700)(-1900 1700);
WIRE 16 -1 (-1700 1700)(-1900 1700);
WIRE 16 -1 (-1900 775)(-4125 775);
WIRE 16 -1 (-1700 1700)(-1275 1700);
WIRE 16 -1 (-1700 1700)(-1700 1625);
WIRE 16 -1 (-1275 1800)(-1275 1700);
WIRE 16 -1 (-1275 1700)(-1275 1625);
WIRE 16 -1 (-4600 2050)(-3725 2050);
FORCEPROP 2 LAST SIG_NAME SW_PVDDCR_CPU0_P0_BOOT2_RC
J 2
(-3760 2060);
DISPLAY 0.489362 (-3760 2060);
FORCEPROP 2 LASTPROP $XRERR UNIQUE?
J 0
(-4000 2060);
DISPLAY 0.638298 (-4000 2060);
PAINT MONO (-4000 2060);
DISPLAY INVISIBLE (-4000 2060);
WIRE 16 -1 (-3725 2050)(-3725 2025);
WIRE 16 -1 (-3875 1450)(-3450 1450);
FORCEPROP 2 LAST SIG_NAME IND_CPU0_P0_CPL1
J 0
(-3860 1460);
DISPLAY 0.489362 (-3860 1460);
WIRE 16 -1 (-3500 5425)(-3500 5500);
WIRE 16 -1 (-3150 5500)(-3500 5500);
WIRE 16 -1 (-3500 5500)(-3925 5500);
WIRE 16 -1 (-3925 5425)(-3925 5500);
WIRE 16 -1 (-4000 5500)(-3925 5500);
WIRE 16 -1 (-4000 5550)(-4000 5500);
WIRE 16 -1 (-4000 5500)(-4250 5500);
WIRE 16 -1 (-4250 5500)(-4250 5425);
WIRE 16 -1 (-4550 5500)(-4250 5500);
WIRE 16 -1 (-4550 5500)(-4550 5425);
WIRE 16 -1 (-4875 5500)(-4550 5500);
WIRE 16 -1 (-4875 5425)(-4875 5500);
WIRE 16 -1 (-5200 5500)(-4875 5500);
WIRE 16 -1 (-5200 5425)(-5200 5500);
WIRE 16 -1 (-5525 5500)(-5200 5500);
WIRE 16 -1 (-5525 5425)(-5525 5500);
WIRE 16 -1 (-5675 5500)(-5525 5500);
WIRE 16 -1 (-5675 5500)(-5675 5100);
WIRE 16 -1 (-5775 5100)(-5675 5100);
WIRE 16 -1 (-5675 5100)(-5675 5050);
WIRE 16 -1 (-5675 5050)(-5775 5050);
WIRE 16 -1 (-6625 3850)(-7225 3850);
FORCEPROP 2 LAST SIG_NAME PVDDCR_CPU0_P0_PWM1
J 2
(-6685 3860);
DISPLAY 0.489362 (-6685 3860);
WIRE 16 -1 (-5525 2475)(-5525 2350);
WIRE 16 -1 (-5525 2350)(-5200 2350);
WIRE 16 -1 (-5200 2350)(-4875 2350);
WIRE 16 -1 (-5200 2475)(-5200 2350);
WIRE 16 -1 (-4875 2350)(-4550 2350);
WIRE 16 -1 (-4875 2475)(-4875 2350);
WIRE 16 -1 (-4250 2350)(-4550 2350);
WIRE 16 -1 (-4550 2475)(-4550 2350);
WIRE 16 -1 (-4250 2475)(-4250 2350);
WIRE 16 -1 (-4250 2350)(-4250 2275);
WIRE 16 -1 (-5750 1450)(-5000 1450);
WIRE 16 -1 (-5000 775)(-5000 1450);
WIRE 16 -1 (-4325 775)(-5000 775);
FORCEPROP 2 LAST SIG_NAME PVDDCR_CPU0_P0_VOS2
J 0
(-5635 1475);
DISPLAY 0.489362 (-5635 1475);
FORCEPROP 2 LASTPROP $XRERR UNIQUE?
J 0
(-5875 1475);
DISPLAY 0.638298 (-5875 1475);
PAINT MONO (-5875 1475);
DISPLAY INVISIBLE (-5875 1475);
WIRE 16 -1 (-2100 4450)(-2100 3500);
WIRE 16 -1 (-2100 4450)(-1975 4450);
WIRE 16 -1 (-2825 4450)(-2100 4450);
WIRE 16 -1 (-2100 3500)(-4250 3500);
WIRE 16 -1 (-1600 4450)(-1975 4450);
WIRE 16 -1 (-1975 4375)(-1975 4450);
WIRE 16 -1 (-1150 4450)(-1600 4450);
WIRE 16 -1 (-1600 4450)(-1600 4375);
WIRE 16 -1 (-750 4450)(-1150 4450);
WIRE 16 -1 (-1150 4450)(-1150 4375);
WIRE 16 -1 (-750 4575)(-750 4450);
WIRE 16 -1 (-750 4450)(-750 4350);
WIRE 16 -1 (-4275 4200)(-3625 4200);
FORCEPROP 2 LAST SIG_NAME IND_CPU0_P0_CPL5
J 0
(-4210 4235);
DISPLAY 0.489362 (-4210 4235);
WIRE 16 -1 (-5775 4800)(-4925 4800);
FORCEPROP 2 LAST SIG_NAME SW_PVDDCR_CPU0_P0_BOOT1
J 0
(-5660 4825);
DISPLAY 0.489362 (-5660 4825);
FORCEPROP 2 LASTPROP $XRERR UNIQUE?
J 0
(-5900 4825);
DISPLAY 0.638298 (-5900 4825);
PAINT MONO (-5900 4825);
DISPLAY INVISIBLE (-5900 4825);
WIRE 16 -1 (-6625 4200)(-7075 4200);
FORCEPROP 2 LAST SIG_NAME NC_PVDDCR_CPU0_P0_DNC1
J 2
(-6685 4210);
DISPLAY 0.489362 (-6685 4210);
FORCEPROP 2 LASTPROP $XRERR UNIQUE?
J 0
(-7315 4200);
DISPLAY 0.638298 (-7315 4200);
PAINT MONO (-7315 4200);
DISPLAY INVISIBLE (-7315 4200);
WIRE 16 -1 (-7225 4150)(-6625 4150);
FORCEPROP 2 LAST SIG_NAME PVDDCR_CPU0_P0_LSET1
J 2
(-6685 4160);
DISPLAY 0.489362 (-6685 4160);
FORCEPROP 2 LASTPROP $XRERR UNIQUE?
J 0
(-6925 4160);
DISPLAY 0.638298 (-6925 4160);
PAINT MONO (-6925 4160);
DISPLAY INVISIBLE (-6925 4160);
WIRE 16 -1 (-6625 3950)(-7250 3950);
FORCEPROP 2 LAST SIG_NAME PVDDCR_CPU0_P0_TEMP0
J 2
(-6685 3960);
DISPLAY 0.489362 (-6685 3960);
WIRE 16 -1 (-8000 4275)(-8000 4350);
WIRE 16 -1 (-6625 4350)(-8000 4350);
FORCEPROP 2 LAST SIG_NAME PVDDCR_CPU0_P0_VCCS
J 2
(-6685 4360);
DISPLAY 0.489362 (-6685 4360);
WIRE 16 -1 (-8175 4350)(-8000 4350);
DOT 1 (-4625 1700);
DOT 1 (-2800 3100);
DOT 1 (-5200 2350);
DOT 1 (-2150 2650);
DOT 1 (-4550 2350);
DOT 1 (-4875 2350);
DOT 1 (-4800 4450);
DOT 1 (-1975 4450);
DOT 1 (-5200 5100);
DOT 1 (-4875 5100);
DOT 1 (-5600 1150);
DOT 1 (-4250 2750);
DOT 1 (-4250 5100);
DOT 1 (-3500 5500);
DOT 1 (-4875 5500);
DOT 1 (-3925 5100);
DOT 1 (-4000 5500);
DOT 1 (-3925 5500);
DOT 1 (-8250 5550);
DOT 1 (-7975 1600);
DOT 1 (-7150 2050);
DOT 1 (-7625 2225);
DOT 1 (-7625 2775);
DOT 1 (-7275 2775);
DOT 1 (-5600 1100);
DOT 1 (-5600 1200);
DOT 1 (-5650 2350);
DOT 1 (-5600 3850);
DOT 1 (-5600 3900);
DOT 1 (-5600 3950);
DOT 1 (-4875 2750);
DOT 1 (-4250 2350);
DOT 1 (-4550 2750);
DOT 1 (-8000 4350);
DOT 1 (-7950 4975);
DOT 1 (-7200 4800);
DOT 1 (-7950 5550);
DOT 1 (-7775 5550);
DOT 1 (-7600 5550);
DOT 1 (-5675 5100);
DOT 1 (-5525 5500);
DOT 1 (-5200 5500);
DOT 1 (-4550 5100);
DOT 1 (-4550 5500);
DOT 1 (-4250 5500);
DOT 1 (-2800 2650);
DOT 1 (-2475 2650);
DOT 1 (-2150 3100);
DOT 1 (-1700 1700);
DOT 1 (-1275 1300);
DOT 1 (-1600 4050);
DOT 1 (-1150 4050);
DOT 1 (-750 4050);
DOT 1 (-4000 5100);
DOT 1 (-1600 4450);
DOT 1 (-1150 4450);
DOT 1 (-750 4450);
DOT 1 (-2100 4450);
DOT 1 (-5200 2750);
DOT 1 (-5525 2750);
DOT 1 (-1900 1700);
DOT 1 (-1275 1700);
DOT 1 (-2475 3100);
DOT 1 (-1875 3100);
DOT 1 (-1875 2650);
FORCENOTE
PVDDCR_CPU0_P0_PHASE2
(-6725 3025) 0;
DISPLAY LEFT (-6725 3025);
DISPLAY 1.595745 (-6725 3025);
PAINT WHITE (-6725 3025);
FORCENOTE
3RD=CC72204MD03
(-3675 4850) 0;
DISPLAY LEFT (-3675 4850);
DISPLAY 0.638298 (-3675 4850);
PAINT WHITE (-3675 4850);
FORCENOTE
2ND=CC72204MD01
(-3675 4900) 0;
DISPLAY LEFT (-3675 4900);
DISPLAY 0.638298 (-3675 4900);
PAINT WHITE (-3675 4900);
FORCENOTE
2ND=CV+15^0TZ01
(-2800 4500) 0;
DISPLAY LEFT (-2800 4500);
DISPLAY 0.638298 (-2800 4500);
PAINT WHITE (-2800 4500);
FORCENOTE
DCR=2-3,0.27M OHM
(-2800 4550) 0;
DISPLAY LEFT (-2800 4550);
DISPLAY 0.638298 (-2800 4550);
PAINT WHITE (-2800 4550);
FORCENOTE
DCR=1-4,0.105M OHM
(-2800 4600) 0;
DISPLAY LEFT (-2800 4600);
DISPLAY 0.638298 (-2800 4600);
PAINT WHITE (-2800 4600);
FORCENOTE
11.0*7.5*12.5
(-2800 4650) 0;
DISPLAY LEFT (-2800 4650);
DISPLAY 0.638298 (-2800 4650);
PAINT WHITE (-2800 4650);
FORCENOTE
ISAT:70A@100C
(-2800 4700) 0;
DISPLAY LEFT (-2800 4700);
DISPLAY 0.638298 (-2800 4700);
PAINT WHITE (-2800 4700);
FORCENOTE
PGL6303.151HLT
(-2800 4750) 0;
DISPLAY LEFT (-2800 4750);
DISPLAY 0.638298 (-2800 4750);
PAINT WHITE (-2800 4750);
FORCENOTE
ESR=16M OHM
(-3675 5050) 0;
DISPLAY LEFT (-3675 5050);
DISPLAY 0.638298 (-3675 5050);
PAINT WHITE (-3675 5050);
FORCENOTE
IRIPPLE:4.65A
(-3675 5000) 0;
DISPLAY LEFT (-3675 5000);
DISPLAY 0.638298 (-3675 5000);
PAINT WHITE (-3675 5000);
FORCENOTE
8*11.5
(-3675 4950) 0;
DISPLAY LEFT (-3675 4950);
DISPLAY 0.638298 (-3675 4950);
PAINT WHITE (-3675 4950);
FORCENOTE
PVDDCR_CPU0_P0_PHASE1
(-6950 5925) 0;
DISPLAY LEFT (-6950 5925);
DISPLAY 1.595745 (-6950 5925);
PAINT WHITE (-6950 5925);
FORCENOTE
PGL6303.151HLT
(-2625 2000) 0;
DISPLAY LEFT (-2625 2000);
DISPLAY 0.638298 (-2625 2000);
PAINT WHITE (-2625 2000);
FORCENOTE
ISAT:70A@100C
(-2625 1950) 0;
DISPLAY LEFT (-2625 1950);
DISPLAY 0.638298 (-2625 1950);
PAINT WHITE (-2625 1950);
FORCENOTE
11.0*7.5*12.5
(-2625 1900) 0;
DISPLAY LEFT (-2625 1900);
DISPLAY 0.638298 (-2625 1900);
PAINT WHITE (-2625 1900);
FORCENOTE
DCR=1-4,0.105M OHM
(-2625 1850) 0;
DISPLAY LEFT (-2625 1850);
DISPLAY 0.638298 (-2625 1850);
PAINT WHITE (-2625 1850);
FORCENOTE
DCR=2-3,0.27M OHM
(-2625 1800) 0;
DISPLAY LEFT (-2625 1800);
DISPLAY 0.638298 (-2625 1800);
PAINT WHITE (-2625 1800);
FORCENOTE
2ND=CV+15^0TZ01
(-2625 1750) 0;
DISPLAY LEFT (-2625 1750);
DISPLAY 0.638298 (-2625 1750);
PAINT WHITE (-2625 1750);
FORCENOTE
2ND=CVA50^0MZ07
(-3150 5225) 0;
DISPLAY LEFT (-3150 5225);
DISPLAY 0.638298 (-3150 5225);
PAINT WHITE (-3150 5225);
FORCENOTE
3RD=CVA50^0MZ08
(-3150 5175) 0;
DISPLAY LEFT (-3150 5175);
DISPLAY 0.638298 (-3150 5175);
PAINT WHITE (-3150 5175);
FORCENOTE
PR324,PR325,PR350,PR351,PR355,PR433=EMPTY
(-2100 5200) 0;
DISPLAY LEFT (-2100 5200);
DISPLAY 0.638298 (-2100 5200);
PAINT WHITE (-2100 5200);
FORCENOTE
PR446,PR322,PR323,PR348,PR349,PR354,PR432=CS00002JB38
(-2100 5125) 0;
DISPLAY LEFT (-2100 5125);
DISPLAY 0.638298 (-2100 5125);
PAINT WHITE (-2100 5125);
FORCENOTE
DCR=0.09M OHM
(-3150 5275) 0;
DISPLAY LEFT (-3150 5275);
DISPLAY 0.638298 (-3150 5275);
PAINT WHITE (-3150 5275);
FORCENOTE
6.0*6.1*7.0
(-3150 5325) 0;
DISPLAY LEFT (-3150 5325);
DISPLAY 0.638298 (-3150 5325);
PAINT WHITE (-3150 5325);
FORCENOTE
PG2292.500HLT
(-3150 5425) 0;
DISPLAY LEFT (-3150 5425);
DISPLAY 0.638298 (-3150 5425);
PAINT WHITE (-3150 5425);
FORCENOTE
ISAT:70A@100C
(-3150 5375) 0;
DISPLAY LEFT (-3150 5375);
DISPLAY 0.638298 (-3150 5375);
PAINT WHITE (-3150 5375);
FORCENOTE
BOM NOTE
(-2100 6425) 0;
DISPLAY LEFT (-2100 6425);
DISPLAY 1.021277 (-2100 6425);
PAINT WHITE (-2100 6425);
FORCENOTE
MAIN SOURCE:RENESAS BOM
(-2100 6325) 0;
DISPLAY LEFT (-2100 6325);
DISPLAY 0.638298 (-2100 6325);
PAINT WHITE (-2100 6325);
FORCENOTE
PU6,PU43,PU46,PU47,PU48,PU10=AL099390004/ISL99390FRZ-TR5935
(-2100 6225) 0;
DISPLAY LEFT (-2100 6225);
DISPLAY 0.638298 (-2100 6225);
PAINT WHITE (-2100 6225);
FORCENOTE
2ND SOURCE:INFENEON BOM
(-2100 6050) 0;
DISPLAY LEFT (-2100 6050);
DISPLAY 0.638298 (-2100 6050);
PAINT WHITE (-2100 6050);
FORCENOTE
PR322,PR323,PR348,PR349,PR354,PR432 = CS00002JB38
(-2100 5850) 0;
DISPLAY LEFT (-2100 5850);
DISPLAY 0.638298 (-2100 5850);
PAINT WHITE (-2100 5850);
FORCENOTE
PU6,PU43,PU46,PU47,PU48,PU10=AL087000A02/MP87000GMJTH-C06A-Z
(-2100 5350) 0;
DISPLAY LEFT (-2100 5350);
DISPLAY 0.638298 (-2100 5350);
PAINT WHITE (-2100 5350);
FORCENOTE
PR445,PC473_1,PC474_2,PC544_3,PC545_4,PC566_5,PC150_6=EMPTY
(-2100 5275) 0;
DISPLAY LEFT (-2100 5275);
DISPLAY 0.638298 (-2100 5275);
PAINT WHITE (-2100 5275);
FORCENOTE
PU6,PU43,PU46,PU47,PU48,PU10 = AL021590000/TDA21590
(-2100 5950) 0;
DISPLAY LEFT (-2100 5950);
DISPLAY 0.638298 (-2100 5950);
PAINT WHITE (-2100 5950);
FORCENOTE
3RD SOURCE:MPS BOM
(-2100 5450) 0;
DISPLAY LEFT (-2100 5450);
DISPLAY 0.638298 (-2100 5450);
PAINT WHITE (-2100 5450);
FORCENOTE
PC473_1,PC474_2,PC544_3,PC545_4,PC566_5,PC150_6 = EMPTY
(-2100 5650) 0;
DISPLAY LEFT (-2100 5650);
DISPLAY 0.638298 (-2100 5650);
PAINT WHITE (-2100 5650);
FORCENOTE
PR324,PR325,PR350,PR351,PR355,PR433 = EMPTY
(-2100 5750) 0;
DISPLAY LEFT (-2100 5750);
DISPLAY 0.638298 (-2100 5750);
PAINT WHITE (-2100 5750);
FORCENOTE
PR320,PR321,PR346,PR347,PR353,PR431 = CS00002JB38
(-2100 5550) 0;
DISPLAY LEFT (-2100 5550);
DISPLAY 0.638298 (-2100 5550);
PAINT WHITE (-2100 5550);
FORCENOTE
2ND=CH722KM8804
(-2500 2400) 0;
DISPLAY LEFT (-2500 2400);
DISPLAY 0.638298 (-2500 2400);
PAINT WHITE (-2500 2400);
FORCENOTE
MAIN=CH122KM8801
(-2500 2450) 0;
DISPLAY LEFT (-2500 2450);
DISPLAY 0.638298 (-2500 2450);
PAINT WHITE (-2500 2450);
FORCENOTE
7.3*4.3*1.9
(-2500 2500) 0;
DISPLAY LEFT (-2500 2500);
DISPLAY 0.638298 (-2500 2500);
PAINT WHITE (-2500 2500);
FORCENOTE
ESR=9.0M OHM
(-2500 2550) 0;
DISPLAY LEFT (-2500 2550);
DISPLAY 0.638298 (-2500 2550);
PAINT WHITE (-2500 2550);
QUIT
